FILE_TYPE = MACRO_DRAWING;
SET COLOR_WIRE YELLOW;
SET COLOR_PROP MONO;
SET COLOR_DOT WHITE;
SET COLOR_ARC YELLOW;
SET COLOR_BODY GREEN;
SET COLOR_NOTE MONO;
SET PROP_DISPLAY VALUE;
SET PAGE_NUMBER P156;
FORCEADD OFFPAGE..1
(-4625 4200);
FORCEPROP 2 LAST $XR0 145 
J 0
(-4877 4200);
DISPLAY 0.638298 (-4877 4200);
PAINT MONO (-4877 4200);
FORCEPROP 1 LAST COMMENT_BODY TRUE
J 0
(-4500 4100);
DISPLAY 0.872340 (-4500 4100);
PAINT GREEN (-4500 4100);
DISPLAY INVISIBLE (-4500 4100);
FORCEPROP 1 LAST OFFPAGE TRUE
J 0
(-4300 4075);
DISPLAY 0.872340 (-4300 4075);
PAINT GREEN (-4300 4075);
DISPLAY INVISIBLE (-4300 4075);
FORCEPROP 2 LAST PATH I202
J 0
(-4575 4275);
DISPLAY 1.021277 (-4575 4275);
PAINT ORANGE (-4575 4275);
DISPLAY INVISIBLE (-4575 4275);
FORCEPROP 2 LAST CDS_LIB mstr_standard
J 0
(-4625 4200);
PAINT ORANGE (-4625 4200);
DISPLAY INVISIBLE (-4625 4200);
FORCEADD OFFPAGE..1
(-4625 4100);
FORCEPROP 2 LAST $XR0 145 
J 0
(-4877 4100);
DISPLAY 0.638298 (-4877 4100);
PAINT MONO (-4877 4100);
FORCEPROP 2 LAST CDS_LIB mstr_standard
J 0
(-4625 4100);
PAINT ORANGE (-4625 4100);
DISPLAY INVISIBLE (-4625 4100);
FORCEPROP 2 LAST PATH I203
J 0
(-4575 4175);
DISPLAY 1.021277 (-4575 4175);
PAINT ORANGE (-4575 4175);
DISPLAY INVISIBLE (-4575 4175);
FORCEPROP 1 LAST OFFPAGE TRUE
J 0
(-4300 3975);
DISPLAY 0.872340 (-4300 3975);
PAINT GREEN (-4300 3975);
DISPLAY INVISIBLE (-4300 3975);
FORCEPROP 1 LAST COMMENT_BODY TRUE
J 0
(-4500 4000);
DISPLAY 0.872340 (-4500 4000);
PAINT GREEN (-4500 4000);
DISPLAY INVISIBLE (-4500 4000);
FORCEADD OFFPAGE..2
(-700 4200);
FORCEPROP 2 LASTPIN (-750 4200) SIG_NAME RST_BMC_SYSRST_BTN_OUT_B_N
J 2
(-760 4210);
DISPLAY 0.617021 (-760 4210);
PAINT ORANGE (-760 4210);
FORCEPROP 2 LAST $XR1 118 
J 0
(-391 4200);
DISPLAY 0.638298 (-391 4200);
PAINT MONO (-391 4200);
FORCEPROP 2 LAST $XR0 191 
J 0
(-511 4200);
DISPLAY 0.638298 (-511 4200);
PAINT MONO (-511 4200);
FORCEPROP 2 LAST PATH I204
J 0
(-650 4275);
DISPLAY 1.021277 (-650 4275);
PAINT ORANGE (-650 4275);
DISPLAY INVISIBLE (-650 4275);
FORCEPROP 2 LAST CDS_LIB mstr_standard
J 0
(-700 4200);
PAINT ORANGE (-700 4200);
DISPLAY INVISIBLE (-700 4200);
FORCEPROP 1 LAST OFFPAGE TRUE
J 0
(-375 4075);
DISPLAY 0.872340 (-375 4075);
PAINT GREEN (-375 4075);
DISPLAY INVISIBLE (-375 4075);
FORCEPROP 1 LAST COMMENT_BODY TRUE
J 0
(-745 4105);
DISPLAY 0.872340 (-745 4105);
PAINT GREEN (-745 4105);
DISPLAY INVISIBLE (-745 4105);
FORCEADD OFFPAGE..2
(-700 4100);
FORCEPROP 2 LASTPIN (-750 4100) SIG_NAME FM_PCH_PWRBTN_N
J 2
(-760 4110);
DISPLAY 0.617021 (-760 4110);
PAINT ORANGE (-760 4110);
FORCEPROP 2 LAST $XR1 118 
J 0
(-391 4100);
DISPLAY 0.638298 (-391 4100);
PAINT MONO (-391 4100);
FORCEPROP 2 LAST $XR0 191 
J 0
(-511 4100);
DISPLAY 0.638298 (-511 4100);
PAINT MONO (-511 4100);
FORCEPROP 2 LAST CDS_LIB mstr_standard
J 0
(-700 4100);
PAINT ORANGE (-700 4100);
DISPLAY INVISIBLE (-700 4100);
FORCEPROP 2 LAST PATH I205
J 0
(-525 4175);
DISPLAY 1.021277 (-525 4175);
PAINT ORANGE (-525 4175);
DISPLAY INVISIBLE (-525 4175);
FORCEPROP 1 LAST OFFPAGE TRUE
J 0
(-375 3975);
DISPLAY 0.872340 (-375 3975);
PAINT GREEN (-375 3975);
DISPLAY INVISIBLE (-375 3975);
FORCEPROP 1 LAST COMMENT_BODY TRUE
J 0
(-745 4005);
DISPLAY 0.872340 (-745 4005);
PAINT GREEN (-745 4005);
DISPLAY INVISIBLE (-745 4005);
FORCEADD RES..2
(-4150 4450);
FORCEPROP 1 LASTPIN (-4150 4550) $PN 1
J 0
(-4145 4512);
DISPLAY 0.617021 (-4145 4512);
PAINT ORANGE (-4145 4512);
FORCEPROP 1 LASTPIN (-4150 4350) $PN 2
J 0
(-4145 4360);
DISPLAY 0.617021 (-4145 4360);
PAINT ORANGE (-4145 4360);
FORCEPROP 1 LAST MATERIAL CHIP
J 0
(-4110 4375);
DISPLAY 0.617021 (-4110 4375);
PAINT SKYBLUE (-4110 4375);
FORCEPROP 1 LAST PACK_TYPE 0402
J 0
(-4110 4275);
DISPLAY 0.617021 (-4110 4275);
PAINT SKYBLUE (-4110 4275);
FORCEPROP 1 LAST TOLERANCE 1%
J 0
(-4105 4475);
DISPLAY 0.617021 (-4105 4475);
PAINT SKYBLUE (-4105 4475);
FORCEPROP 1 LAST PART_NUMBER G21796-072
J 0
(-4110 4325);
DISPLAY 0.617021 (-4110 4325);
PAINT BLUE (-4110 4325);
FORCEPROP 1 LAST WATTAGE 1/16W
J 0
(-4110 4425);
DISPLAY 0.617021 (-4110 4425);
PAINT SKYBLUE (-4110 4425);
FORCEPROP 1 LAST VALUE 4.75K
J 0
(-4105 4525);
DISPLAY 0.617021 (-4105 4525);
PAINT SKYBLUE (-4105 4525);
FORCEPROP 1 LAST LOCATION R2T34
J 0
(-4105 4575);
DISPLAY 0.617021 (-4105 4575);
PAINT AQUA (-4105 4575);
FORCEPROP 2 LAST CDS_LOCATION R2T34
J 0
(-4105 4575);
DISPLAY 0.617021 (-4105 4575);
PAINT AQUA (-4105 4575);
DISPLAY INVISIBLE (-4105 4575);
FORCEPROP 2 LAST CDS_LIB mstr_discrete
J 0
(-4150 4450);
PAINT MONO (-4150 4450);
DISPLAY INVISIBLE (-4150 4450);
FORCEPROP 2 LAST BOM_COST SM_CONTROLLER
J 0
(-4100 4675);
DISPLAY 1.021277 (-4100 4675);
PAINT ORANGE (-4100 4675);
DISPLAY INVISIBLE (-4100 4675);
FORCEPROP 2 LAST SEC_TYPE 0402
J 0
(-4100 4675);
DISPLAY 1.021277 (-4100 4675);
PAINT ORANGE (-4100 4675);
DISPLAY INVISIBLE (-4100 4675);
FORCEPROP 2 LAST SEC 1
J 0
(-4100 4675);
PAINT MONO (-4100 4675);
DISPLAY INVISIBLE (-4100 4675);
FORCEPROP 1 LAST PATH I206
J 0
(-4100 4625);
DISPLAY 0.978723 (-4100 4625);
PAINT WHITE (-4100 4625);
DISPLAY INVISIBLE (-4100 4625);
FORCEPROP 2 LAST ROOM BMC_MISC
J 0
(-4100 4625);
DISPLAY 1.021277 (-4100 4625);
PAINT ORANGE (-4100 4625);
DISPLAY INVISIBLE (-4100 4625);
FORCEADD RES..2
(-3825 4450);
FORCEPROP 1 LAST VALUE 4.75K
J 0
(-3780 4525);
DISPLAY 0.617021 (-3780 4525);
PAINT SKYBLUE (-3780 4525);
FORCEPROP 1 LAST WATTAGE 1/16W
J 0
(-3785 4425);
DISPLAY 0.617021 (-3785 4425);
PAINT SKYBLUE (-3785 4425);
FORCEPROP 1 LAST PART_NUMBER G21796-072
J 0
(-3785 4325);
DISPLAY 0.617021 (-3785 4325);
PAINT BLUE (-3785 4325);
FORCEPROP 1 LAST PACK_TYPE 0402
J 0
(-3785 4275);
DISPLAY 0.617021 (-3785 4275);
PAINT SKYBLUE (-3785 4275);
FORCEPROP 1 LAST LOCATION R2T35
J 0
(-3780 4575);
DISPLAY 0.617021 (-3780 4575);
PAINT AQUA (-3780 4575);
FORCEPROP 1 LASTPIN (-3825 4350) $PN 2
J 0
(-3820 4360);
DISPLAY 0.617021 (-3820 4360);
PAINT ORANGE (-3820 4360);
FORCEPROP 1 LAST TOLERANCE 1%
J 0
(-3780 4475);
DISPLAY 0.617021 (-3780 4475);
PAINT SKYBLUE (-3780 4475);
FORCEPROP 1 LASTPIN (-3825 4550) $PN 1
J 0
(-3820 4512);
DISPLAY 0.617021 (-3820 4512);
PAINT ORANGE (-3820 4512);
FORCEPROP 1 LAST MATERIAL CHIP
J 0
(-3785 4375);
DISPLAY 0.617021 (-3785 4375);
PAINT SKYBLUE (-3785 4375);
FORCEPROP 2 LAST CDS_LOCATION R2T35
J 0
(-3780 4575);
DISPLAY 0.617021 (-3780 4575);
PAINT AQUA (-3780 4575);
DISPLAY INVISIBLE (-3780 4575);
FORCEPROP 2 LAST CDS_LIB mstr_discrete
J 0
(-3825 4450);
PAINT MONO (-3825 4450);
DISPLAY INVISIBLE (-3825 4450);
FORCEPROP 1 LAST PATH I207
J 0
(-3775 4625);
DISPLAY 0.978723 (-3775 4625);
PAINT WHITE (-3775 4625);
DISPLAY INVISIBLE (-3775 4625);
FORCEPROP 2 LAST SEC_TYPE 0402
J 0
(-3775 4675);
DISPLAY 1.021277 (-3775 4675);
PAINT ORANGE (-3775 4675);
DISPLAY INVISIBLE (-3775 4675);
FORCEPROP 2 LAST BOM_COST SM_CONTROLLER
J 0
(-3775 4675);
DISPLAY 1.021277 (-3775 4675);
PAINT ORANGE (-3775 4675);
DISPLAY INVISIBLE (-3775 4675);
FORCEPROP 2 LAST SEC 1
J 0
(-3775 4675);
PAINT MONO (-3775 4675);
DISPLAY INVISIBLE (-3775 4675);
FORCEPROP 2 LAST ROOM BMC_MISC
J 0
(-3775 4625);
DISPLAY 1.021277 (-3775 4625);
PAINT ORANGE (-3775 4625);
DISPLAY INVISIBLE (-3775 4625);
FORCEADD P3V3_STBY..1
(-4150 4850);
FORCEPROP 3 LASTPIN (-4150 4800) SIG_NAME P3V3_STBY\g
J 0
(-4140 4810);
DISPLAY 0.659574 (-4140 4810);
PAINT MONO (-4140 4810);
DISPLAY INVISIBLE (-4140 4810);
FORCEPROP 1 LAST VOLTAGE 3.3V
J 0
(-4195 4807);
DISPLAY 0.340426 (-4195 4807);
PAINT SKYBLUE (-4195 4807);
DISPLAY INVISIBLE (-4195 4807);
FORCEPROP 2 LAST CDS_LIB mstr_symbols
J 0
(-4150 4850);
PAINT ORANGE (-4150 4850);
DISPLAY INVISIBLE (-4150 4850);
FORCEPROP 1 LAST PATH I208
J 0
(-4105 4852);
DISPLAY 0.340426 (-4105 4852);
PAINT GREEN (-4105 4852);
DISPLAY INVISIBLE (-4105 4852);
FORCEPROP 1 LAST SIZE 1B
J 0
(-4105 4872);
DISPLAY 0.340426 (-4105 4872);
PAINT GREEN (-4105 4872);
DISPLAY INVISIBLE (-4105 4872);
FORCEPROP 1 LAST BODY_TYPE PLUMBING
J 0
(-4195 4807);
DISPLAY 0.340426 (-4195 4807);
PAINT GREEN (-4195 4807);
DISPLAY INVISIBLE (-4195 4807);
FORCEPROP 1 LAST HDL_POWER P3V3_STBY
J 0
(-4450 4725);
DISPLAY 0.872340 (-4450 4725);
PAINT ORANGE (-4450 4725);
DISPLAY INVISIBLE (-4450 4725);
FORCEADD P3V3_STBY..1
(-2400 4850);
FORCEPROP 3 LASTPIN (-2400 4800) SIG_NAME P3V3_STBY\g
J 0
(-2390 4810);
DISPLAY 0.659574 (-2390 4810);
PAINT MONO (-2390 4810);
DISPLAY INVISIBLE (-2390 4810);
FORCEPROP 1 LAST VOLTAGE 3.3V
J 0
(-2445 4807);
DISPLAY 0.340426 (-2445 4807);
PAINT SKYBLUE (-2445 4807);
DISPLAY INVISIBLE (-2445 4807);
FORCEPROP 1 LAST PATH I209
J 0
(-2355 4852);
DISPLAY 0.340426 (-2355 4852);
PAINT GREEN (-2355 4852);
DISPLAY INVISIBLE (-2355 4852);
FORCEPROP 2 LAST CDS_LIB mstr_symbols
J 0
(-2400 4850);
PAINT ORANGE (-2400 4850);
DISPLAY INVISIBLE (-2400 4850);
FORCEPROP 1 LAST SIZE 1B
J 0
(-2355 4872);
DISPLAY 0.340426 (-2355 4872);
PAINT GREEN (-2355 4872);
DISPLAY INVISIBLE (-2355 4872);
FORCEPROP 1 LAST BODY_TYPE PLUMBING
J 0
(-2445 4807);
DISPLAY 0.340426 (-2445 4807);
PAINT GREEN (-2445 4807);
DISPLAY INVISIBLE (-2445 4807);
FORCEPROP 1 LAST HDL_POWER P3V3_STBY
J 0
(-2700 4725);
DISPLAY 0.872340 (-2700 4725);
PAINT ORANGE (-2700 4725);
DISPLAY INVISIBLE (-2700 4725);
FORCEADD RES..2
(-2275 4425);
FORCEPROP 1 LAST WATTAGE 1/16W
J 0
(-2235 4400);
DISPLAY 0.617021 (-2235 4400);
PAINT SKYBLUE (-2235 4400);
FORCEPROP 1 LAST PART_NUMBER G21796-016
J 0
(-2235 4300);
DISPLAY 0.617021 (-2235 4300);
PAINT BLUE (-2235 4300);
FORCEPROP 1 LAST TOLERANCE 1%
J 0
(-2230 4450);
DISPLAY 0.617021 (-2230 4450);
PAINT SKYBLUE (-2230 4450);
FORCEPROP 1 LAST VALUE 10.0K
J 0
(-2230 4500);
DISPLAY 0.617021 (-2230 4500);
PAINT SKYBLUE (-2230 4500);
FORCEPROP 1 LAST LOCATION R2T22
J 0
(-2230 4550);
DISPLAY 0.617021 (-2230 4550);
PAINT AQUA (-2230 4550);
FORCEPROP 1 LASTPIN (-2275 4525) $PN 1
J 0
(-2270 4487);
DISPLAY 0.617021 (-2270 4487);
PAINT ORANGE (-2270 4487);
FORCEPROP 1 LAST PACK_TYPE 0402
J 0
(-2235 4250);
DISPLAY 0.617021 (-2235 4250);
PAINT SKYBLUE (-2235 4250);
FORCEPROP 1 LASTPIN (-2275 4325) $PN 2
J 0
(-2270 4335);
DISPLAY 0.617021 (-2270 4335);
PAINT ORANGE (-2270 4335);
FORCEPROP 1 LAST MATERIAL CHIP
J 0
(-2235 4350);
DISPLAY 0.617021 (-2235 4350);
PAINT SKYBLUE (-2235 4350);
FORCEPROP 2 LAST CDS_LIB mstr_discrete
J 0
(-2275 4425);
PAINT ORANGE (-2275 4425);
DISPLAY INVISIBLE (-2275 4425);
FORCEPROP 2 LAST CDS_LOCATION R2T22
J 0
(-2230 4550);
DISPLAY 0.617021 (-2230 4550);
PAINT AQUA (-2230 4550);
DISPLAY INVISIBLE (-2230 4550);
FORCEPROP 1 LAST PATH I210
J 0
(-2225 4600);
DISPLAY 0.978723 (-2225 4600);
PAINT WHITE (-2225 4600);
DISPLAY INVISIBLE (-2225 4600);
FORCEPROP 2 LAST ROOM BMC_MISC
J 0
(-2225 4600);
DISPLAY 1.021277 (-2225 4600);
PAINT ORANGE (-2225 4600);
DISPLAY INVISIBLE (-2225 4600);
FORCEPROP 2 LAST SEC 1
J 0
(-2225 4650);
DISPLAY 0.680851 (-2225 4650);
PAINT MONO (-2225 4650);
DISPLAY INVISIBLE (-2225 4650);
FORCEPROP 2 LAST SEC_TYPE 0402
J 0
(-2225 4650);
DISPLAY 1.021277 (-2225 4650);
PAINT ORANGE (-2225 4650);
DISPLAY INVISIBLE (-2225 4650);
FORCEPROP 2 LAST BOM_COST SM_CONTROLLER
J 0
(-2225 4650);
DISPLAY 1.021277 (-2225 4650);
PAINT ORANGE (-2225 4650);
DISPLAY INVISIBLE (-2225 4650);
FORCEADD RES..2
(-2550 4450);
FORCEPROP 1 LAST LOCATION R8F26
J 0
(-2505 4575);
DISPLAY 0.617021 (-2505 4575);
PAINT AQUA (-2505 4575);
FORCEPROP 1 LAST PACK_TYPE 0402
J 0
(-2510 4275);
DISPLAY 0.617021 (-2510 4275);
PAINT SKYBLUE (-2510 4275);
FORCEPROP 1 LAST WATTAGE 1/16W
J 0
(-2510 4425);
DISPLAY 0.617021 (-2510 4425);
PAINT SKYBLUE (-2510 4425);
FORCEPROP 1 LAST TOLERANCE 1%
J 0
(-2505 4475);
DISPLAY 0.617021 (-2505 4475);
PAINT SKYBLUE (-2505 4475);
FORCEPROP 1 LASTPIN (-2550 4550) $PN 1
J 0
(-2545 4512);
DISPLAY 0.617021 (-2545 4512);
PAINT ORANGE (-2545 4512);
FORCEPROP 1 LASTPIN (-2550 4350) $PN 2
J 0
(-2545 4360);
DISPLAY 0.617021 (-2545 4360);
PAINT ORANGE (-2545 4360);
FORCEPROP 1 LAST MATERIAL CHIP
J 0
(-2510 4375);
DISPLAY 0.617021 (-2510 4375);
PAINT SKYBLUE (-2510 4375);
FORCEPROP 1 LAST PART_NUMBER G21796-016
J 0
(-2510 4325);
DISPLAY 0.617021 (-2510 4325);
PAINT BLUE (-2510 4325);
FORCEPROP 1 LAST VALUE 10.0K
J 0
(-2505 4525);
DISPLAY 0.617021 (-2505 4525);
PAINT SKYBLUE (-2505 4525);
FORCEPROP 2 LAST CDS_LOCATION R8F26
J 0
(-2505 4575);
DISPLAY 0.617021 (-2505 4575);
PAINT AQUA (-2505 4575);
DISPLAY INVISIBLE (-2505 4575);
FORCEPROP 2 LAST CDS_LIB mstr_discrete
J 0
(-2550 4450);
PAINT ORANGE (-2550 4450);
DISPLAY INVISIBLE (-2550 4450);
FORCEPROP 2 LAST ROOM BMC_MISC
J 0
(-2500 4625);
DISPLAY 1.021277 (-2500 4625);
PAINT ORANGE (-2500 4625);
DISPLAY INVISIBLE (-2500 4625);
FORCEPROP 1 LAST PATH I211
J 0
(-2500 4625);
DISPLAY 0.978723 (-2500 4625);
PAINT WHITE (-2500 4625);
DISPLAY INVISIBLE (-2500 4625);
FORCEPROP 2 LAST SEC 1
J 0
(-2500 4675);
DISPLAY 0.680851 (-2500 4675);
PAINT MONO (-2500 4675);
DISPLAY INVISIBLE (-2500 4675);
FORCEPROP 2 LAST SEC_TYPE 0402
J 0
(-2500 4675);
DISPLAY 1.021277 (-2500 4675);
PAINT ORANGE (-2500 4675);
DISPLAY INVISIBLE (-2500 4675);
FORCEPROP 2 LAST BOM_COST SM_CONTROLLER
J 0
(-2500 4675);
DISPLAY 1.021277 (-2500 4675);
PAINT ORANGE (-2500 4675);
DISPLAY INVISIBLE (-2500 4675);
FORCEADD OFFPAGE..1
(-7525 2775);
FORCEPROP 2 LAST $XR1 145 
J 0
(-7897 2775);
DISPLAY 0.638298 (-7897 2775);
PAINT MONO (-7897 2775);
FORCEPROP 2 LAST $XR0 120 
J 0
(-7777 2775);
DISPLAY 0.638298 (-7777 2775);
PAINT MONO (-7777 2775);
FORCEPROP 1 LAST COMMENT_BODY TRUE
J 0
(-7400 2675);
DISPLAY 0.872340 (-7400 2675);
PAINT GREEN (-7400 2675);
DISPLAY INVISIBLE (-7400 2675);
FORCEPROP 1 LAST OFFPAGE TRUE
J 0
(-7200 2650);
DISPLAY 0.872340 (-7200 2650);
PAINT GREEN (-7200 2650);
DISPLAY INVISIBLE (-7200 2650);
FORCEPROP 2 LAST PATH I212
J 0
(-7475 2850);
DISPLAY 1.021277 (-7475 2850);
PAINT ORANGE (-7475 2850);
DISPLAY INVISIBLE (-7475 2850);
FORCEPROP 2 LAST CDS_LIB mstr_standard
J 0
(-7525 2775);
PAINT ORANGE (-7525 2775);
DISPLAY INVISIBLE (-7525 2775);
FORCEADD OFFPAGE..2
(-5850 2775);
FORCEPROP 2 LAST $XR0 119 
J 0
(-5661 2775);
DISPLAY 0.638298 (-5661 2775);
PAINT MONO (-5661 2775);
FORCEPROP 2 LAST CDS_LIB mstr_standard
J 0
(-5850 2775);
PAINT ORANGE (-5850 2775);
DISPLAY INVISIBLE (-5850 2775);
FORCEPROP 2 LAST PATH I213
J 0
(-5800 2850);
DISPLAY 1.021277 (-5800 2850);
PAINT ORANGE (-5800 2850);
DISPLAY INVISIBLE (-5800 2850);
FORCEPROP 1 LAST OFFPAGE TRUE
J 0
(-5525 2650);
DISPLAY 0.872340 (-5525 2650);
PAINT GREEN (-5525 2650);
DISPLAY INVISIBLE (-5525 2650);
FORCEPROP 1 LAST COMMENT_BODY TRUE
J 0
(-5895 2680);
DISPLAY 0.872340 (-5895 2680);
PAINT GREEN (-5895 2680);
DISPLAY INVISIBLE (-5895 2680);
FORCEADD RES..1
(-6575 2775);
FORCEPROP 1 LAST PART_NUMBER G21796-074
J 0
(-6700 2575);
DISPLAY 0.617021 (-6700 2575);
PAINT BLUE (-6700 2575);
FORCEPROP 1 LAST MATERIAL CHIP
J 0
(-6575 2625);
DISPLAY 0.617021 (-6575 2625);
PAINT SKYBLUE (-6575 2625);
FORCEPROP 1 LAST TOLERANCE 1%
J 0
(-6575 2675);
DISPLAY 0.617021 (-6575 2675);
PAINT SKYBLUE (-6575 2675);
FORCEPROP 1 LAST VALUE 33.2
J 2
(-6600 2675);
DISPLAY 0.617021 (-6600 2675);
PAINT SKYBLUE (-6600 2675);
FORCEPROP 1 LASTPIN (-6475 2775) $PN 2
J 0
(-6513 2787);
DISPLAY 0.617021 (-6513 2787);
PAINT ORANGE (-6513 2787);
FORCEPROP 1 LAST LOCATION R8E24
J 0
(-6625 2825);
DISPLAY 0.617021 (-6625 2825);
PAINT AQUA (-6625 2825);
FORCEPROP 1 LASTPIN (-6675 2775) $PN 1
J 0
(-6663 2787);
DISPLAY 0.617021 (-6663 2787);
PAINT ORANGE (-6663 2787);
FORCEPROP 1 LAST WATTAGE 1/16W
J 2
(-6600 2625);
DISPLAY 0.617021 (-6600 2625);
PAINT SKYBLUE (-6600 2625);
FORCEPROP 1 LAST PACK_TYPE 0402
J 0
(-6325 2625);
DISPLAY 0.617021 (-6325 2625);
PAINT SKYBLUE (-6325 2625);
FORCEPROP 2 LAST CDS_LIB mstr_discrete
J 0
(-6575 2775);
PAINT MONO (-6575 2775);
DISPLAY INVISIBLE (-6575 2775);
FORCEPROP 2 LAST SEC_TYPE 0402
J 0
(-6625 2975);
DISPLAY 1.021277 (-6625 2975);
PAINT ORANGE (-6625 2975);
DISPLAY INVISIBLE (-6625 2975);
FORCEPROP 2 LAST BOM_COST SM_CONTROLLER
J 0
(-6625 2975);
DISPLAY 1.021277 (-6625 2975);
PAINT ORANGE (-6625 2975);
DISPLAY INVISIBLE (-6625 2975);
FORCEPROP 2 LAST SEC 1
J 0
(-6625 2975);
DISPLAY 0.680851 (-6625 2975);
PAINT MONO (-6625 2975);
DISPLAY INVISIBLE (-6625 2975);
FORCEPROP 2 LAST CDS_LOCATION R8E24
J 0
(-6625 2825);
DISPLAY 0.617021 (-6625 2825);
PAINT AQUA (-6625 2825);
DISPLAY INVISIBLE (-6625 2825);
FORCEPROP 2 LAST ROOM BMC_MISC
J 0
(-6625 2925);
DISPLAY 1.021277 (-6625 2925);
PAINT ORANGE (-6625 2925);
DISPLAY INVISIBLE (-6625 2925);
FORCEPROP 1 LAST PATH I214
J 0
(-6625 2925);
DISPLAY 0.978723 (-6625 2925);
PAINT WHITE (-6625 2925);
DISPLAY INVISIBLE (-6625 2925);
FORCEADD RES..2
(-6825 3025);
FORCEPROP 1 LAST PACK_TYPE 0402
J 0
(-6785 2850);
DISPLAY 0.617021 (-6785 2850);
PAINT SKYBLUE (-6785 2850);
FORCEPROP 1 LAST PART_NUMBER G21796-072
J 0
(-6785 2900);
DISPLAY 0.617021 (-6785 2900);
PAINT BLUE (-6785 2900);
FORCEPROP 1 LAST LOCATION R8E22
J 0
(-6780 3150);
DISPLAY 0.617021 (-6780 3150);
PAINT AQUA (-6780 3150);
FORCEPROP 1 LAST VALUE 4.75K
J 0
(-6780 3100);
DISPLAY 0.617021 (-6780 3100);
PAINT SKYBLUE (-6780 3100);
FORCEPROP 1 LAST WATTAGE 1/16W
J 0
(-6785 3000);
DISPLAY 0.617021 (-6785 3000);
PAINT SKYBLUE (-6785 3000);
FORCEPROP 1 LASTPIN (-6825 2925) $PN 2
J 0
(-6820 2935);
DISPLAY 0.617021 (-6820 2935);
PAINT ORANGE (-6820 2935);
FORCEPROP 1 LAST MATERIAL CHIP
J 0
(-6785 2950);
DISPLAY 0.617021 (-6785 2950);
PAINT SKYBLUE (-6785 2950);
FORCEPROP 1 LAST TOLERANCE 1%
J 0
(-6780 3050);
DISPLAY 0.617021 (-6780 3050);
PAINT SKYBLUE (-6780 3050);
FORCEPROP 1 LASTPIN (-6825 3125) $PN 1
J 0
(-6820 3087);
DISPLAY 0.617021 (-6820 3087);
PAINT ORANGE (-6820 3087);
FORCEPROP 2 LAST CDS_LIB mstr_discrete
J 0
(-6825 3025);
PAINT ORANGE (-6825 3025);
DISPLAY INVISIBLE (-6825 3025);
FORCEPROP 2 LAST SEC_TYPE 0402
J 0
(-6775 3250);
DISPLAY 1.021277 (-6775 3250);
PAINT ORANGE (-6775 3250);
DISPLAY INVISIBLE (-6775 3250);
FORCEPROP 2 LAST BOM_COST SM_CONTROLLER
J 0
(-6775 3250);
DISPLAY 1.021277 (-6775 3250);
PAINT ORANGE (-6775 3250);
DISPLAY INVISIBLE (-6775 3250);
FORCEPROP 0 LAST SEC 1
J 0
(-6775 3200);
DISPLAY 0.680851 (-6775 3200);
PAINT MONO (-6775 3200);
DISPLAY INVISIBLE (-6775 3200);
FORCEPROP 2 LAST CDS_LOCATION R8E22
J 0
(-6780 3150);
DISPLAY 0.617021 (-6780 3150);
PAINT AQUA (-6780 3150);
DISPLAY INVISIBLE (-6780 3150);
FORCEPROP 1 LAST PATH I215
J 0
(-6775 3200);
DISPLAY 0.978723 (-6775 3200);
PAINT WHITE (-6775 3200);
DISPLAY INVISIBLE (-6775 3200);
FORCEPROP 2 LAST ROOM BMC_MISC
J 0
(-6775 3200);
DISPLAY 1.021277 (-6775 3200);
PAINT ORANGE (-6775 3200);
DISPLAY INVISIBLE (-6775 3200);
FORCEADD P3V3_STBY..1
(-6825 3275);
FORCEPROP 3 LASTPIN (-6825 3225) SIG_NAME P3V3_STBY\g
J 0
(-6815 3235);
DISPLAY 0.659574 (-6815 3235);
PAINT MONO (-6815 3235);
DISPLAY INVISIBLE (-6815 3235);
FORCEPROP 2 LAST CDS_LIB mstr_symbols
J 0
(-6825 3275);
PAINT ORANGE (-6825 3275);
DISPLAY INVISIBLE (-6825 3275);
FORCEPROP 1 LAST VOLTAGE 3.3V
J 0
(-6870 3232);
DISPLAY 0.340426 (-6870 3232);
PAINT SKYBLUE (-6870 3232);
DISPLAY INVISIBLE (-6870 3232);
FORCEPROP 1 LAST SIZE 1B
J 0
(-6780 3297);
DISPLAY 0.340426 (-6780 3297);
PAINT GREEN (-6780 3297);
DISPLAY INVISIBLE (-6780 3297);
FORCEPROP 1 LAST PATH I216
J 0
(-6780 3277);
DISPLAY 0.340426 (-6780 3277);
PAINT GREEN (-6780 3277);
DISPLAY INVISIBLE (-6780 3277);
FORCEPROP 1 LAST BODY_TYPE PLUMBING
J 0
(-6870 3232);
DISPLAY 0.340426 (-6870 3232);
PAINT GREEN (-6870 3232);
DISPLAY INVISIBLE (-6870 3232);
FORCEPROP 1 LAST HDL_POWER P3V3_STBY
J 0
(-7125 3150);
DISPLAY 0.872340 (-7125 3150);
PAINT ORANGE (-7125 3150);
DISPLAY INVISIBLE (-7125 3150);
FORCEADD GND..1
(-7275 4300);
FORCEPROP 3 LASTPIN (-7275 4350) SIG_NAME GND\g
J 0
(-7265 4360);
DISPLAY 0.659574 (-7265 4360);
PAINT MONO (-7265 4360);
DISPLAY INVISIBLE (-7265 4360);
FORCEPROP 1 LAST HDL_POWER GND
J 0
(-7275 4450);
DISPLAY 0.872340 (-7275 4450);
PAINT GREEN (-7275 4450);
DISPLAY INVISIBLE (-7275 4450);
FORCEPROP 1 LAST BODY_TYPE PLUMBING
J 0
(-7320 4257);
DISPLAY 0.340426 (-7320 4257);
PAINT GREEN (-7320 4257);
DISPLAY INVISIBLE (-7320 4257);
FORCEPROP 2 LAST CDS_LIB mstr_symbols
J 0
(-7275 4300);
PAINT MONO (-7275 4300);
DISPLAY INVISIBLE (-7275 4300);
FORCEPROP 1 LAST SIZE 1B
J 0
(-7200 4250);
DISPLAY 0.872340 (-7200 4250);
PAINT AQUA (-7200 4250);
DISPLAY INVISIBLE (-7200 4250);
FORCEPROP 1 LAST PATH I257
J 0
(-7200 4300);
DISPLAY 0.872340 (-7200 4300);
PAINT AQUA (-7200 4300);
DISPLAY INVISIBLE (-7200 4300);
FORCEPROP 1 LAST VOLTAGE 0.0V
J 0
(-7320 4257);
DISPLAY 0.340426 (-7320 4257);
PAINT SKYBLUE (-7320 4257);
DISPLAY INVISIBLE (-7320 4257);
FORCEADD RES..2
(-3825 3250);
FORCEPROP 1 LAST PART_NUMBER G21796-072
J 0
(-3785 3125);
DISPLAY 0.617021 (-3785 3125);
PAINT BLUE (-3785 3125);
FORCEPROP 1 LAST PACK_TYPE 0402
J 0
(-3785 3075);
DISPLAY 0.617021 (-3785 3075);
PAINT SKYBLUE (-3785 3075);
FORCEPROP 1 LAST WATTAGE 1/16W
J 0
(-3785 3225);
DISPLAY 0.617021 (-3785 3225);
PAINT SKYBLUE (-3785 3225);
FORCEPROP 1 LAST TOLERANCE 1%
J 0
(-3780 3275);
DISPLAY 0.617021 (-3780 3275);
PAINT SKYBLUE (-3780 3275);
FORCEPROP 1 LAST VALUE 4.75K
J 0
(-3780 3325);
DISPLAY 0.617021 (-3780 3325);
PAINT SKYBLUE (-3780 3325);
FORCEPROP 1 LAST MATERIAL CHIP
J 0
(-3785 3175);
DISPLAY 0.617021 (-3785 3175);
PAINT SKYBLUE (-3785 3175);
FORCEPROP 1 LASTPIN (-3825 3150) $PN 2
J 0
(-3820 3160);
DISPLAY 0.617021 (-3820 3160);
PAINT ORANGE (-3820 3160);
FORCEPROP 1 LASTPIN (-3825 3350) $PN 1
J 0
(-3820 3312);
DISPLAY 0.617021 (-3820 3312);
PAINT ORANGE (-3820 3312);
FORCEPROP 1 LAST LOCATION R2U2
J 0
(-3780 3375);
DISPLAY 0.617021 (-3780 3375);
PAINT AQUA (-3780 3375);
FORCEPROP 2 LAST CDS_LIB mstr_discrete
J 0
(-3825 3250);
PAINT MONO (-3825 3250);
DISPLAY INVISIBLE (-3825 3250);
FORCEPROP 2 LAST BOM_COST SM_CONTROLLER
J 0
(-3775 3475);
DISPLAY 1.021277 (-3775 3475);
PAINT ORANGE (-3775 3475);
DISPLAY INVISIBLE (-3775 3475);
FORCEPROP 2 LAST SEC_TYPE 0402
J 0
(-3775 3475);
DISPLAY 1.021277 (-3775 3475);
PAINT ORANGE (-3775 3475);
DISPLAY INVISIBLE (-3775 3475);
FORCEPROP 2 LAST SEC 1
J 0
(-3775 3475);
PAINT MONO (-3775 3475);
DISPLAY INVISIBLE (-3775 3475);
FORCEPROP 2 LAST CDS_LOCATION R2U2
J 0
(-3780 3375);
DISPLAY 0.617021 (-3780 3375);
PAINT AQUA (-3780 3375);
DISPLAY INVISIBLE (-3780 3375);
FORCEPROP 1 LAST PATH I265
J 0
(-3775 3425);
DISPLAY 0.978723 (-3775 3425);
PAINT WHITE (-3775 3425);
DISPLAY INVISIBLE (-3775 3425);
FORCEPROP 2 LAST ROOM BMC_MISC
J 0
(-3775 3425);
DISPLAY 1.021277 (-3775 3425);
PAINT ORANGE (-3775 3425);
DISPLAY INVISIBLE (-3775 3425);
FORCEADD P3V3_STBY..1
(-4150 3650);
FORCEPROP 3 LASTPIN (-4150 3600) SIG_NAME P3V3_STBY\g
J 0
(-4140 3610);
DISPLAY 0.659574 (-4140 3610);
PAINT MONO (-4140 3610);
DISPLAY INVISIBLE (-4140 3610);
FORCEPROP 1 LAST VOLTAGE 3.3V
J 0
(-4195 3607);
DISPLAY 0.340426 (-4195 3607);
PAINT SKYBLUE (-4195 3607);
DISPLAY INVISIBLE (-4195 3607);
FORCEPROP 1 LAST SIZE 1B
J 0
(-4105 3672);
DISPLAY 0.340426 (-4105 3672);
PAINT GREEN (-4105 3672);
DISPLAY INVISIBLE (-4105 3672);
FORCEPROP 2 LAST CDS_LIB mstr_symbols
J 0
(-4150 3650);
PAINT ORANGE (-4150 3650);
DISPLAY INVISIBLE (-4150 3650);
FORCEPROP 1 LAST PATH I266
J 0
(-4105 3652);
DISPLAY 0.340426 (-4105 3652);
PAINT GREEN (-4105 3652);
DISPLAY INVISIBLE (-4105 3652);
FORCEPROP 1 LAST BODY_TYPE PLUMBING
J 0
(-4195 3607);
DISPLAY 0.340426 (-4195 3607);
PAINT GREEN (-4195 3607);
DISPLAY INVISIBLE (-4195 3607);
FORCEPROP 1 LAST HDL_POWER P3V3_STBY
J 0
(-4450 3525);
DISPLAY 0.872340 (-4450 3525);
PAINT ORANGE (-4450 3525);
DISPLAY INVISIBLE (-4450 3525);
FORCEADD RES..2
(-4150 3250);
FORCEPROP 1 LAST VALUE 4.75K
J 0
(-4105 3325);
DISPLAY 0.617021 (-4105 3325);
PAINT SKYBLUE (-4105 3325);
FORCEPROP 1 LAST PART_NUMBER G21796-072
J 0
(-4110 3125);
DISPLAY 0.617021 (-4110 3125);
PAINT BLUE (-4110 3125);
FORCEPROP 1 LAST PACK_TYPE 0402
J 0
(-4110 3075);
DISPLAY 0.617021 (-4110 3075);
PAINT SKYBLUE (-4110 3075);
FORCEPROP 1 LAST MATERIAL CHIP
J 0
(-4110 3175);
DISPLAY 0.617021 (-4110 3175);
PAINT SKYBLUE (-4110 3175);
FORCEPROP 1 LAST WATTAGE 1/16W
J 0
(-4110 3225);
DISPLAY 0.617021 (-4110 3225);
PAINT SKYBLUE (-4110 3225);
FORCEPROP 1 LASTPIN (-4150 3150) $PN 2
J 0
(-4145 3160);
DISPLAY 0.617021 (-4145 3160);
PAINT ORANGE (-4145 3160);
FORCEPROP 1 LAST TOLERANCE 1%
J 0
(-4105 3275);
DISPLAY 0.617021 (-4105 3275);
PAINT SKYBLUE (-4105 3275);
FORCEPROP 1 LASTPIN (-4150 3350) $PN 1
J 0
(-4145 3312);
DISPLAY 0.617021 (-4145 3312);
PAINT ORANGE (-4145 3312);
FORCEPROP 1 LAST LOCATION R8G2
J 0
(-4105 3375);
DISPLAY 0.617021 (-4105 3375);
PAINT AQUA (-4105 3375);
FORCEPROP 2 LAST CDS_LIB mstr_discrete
J 0
(-4150 3250);
PAINT MONO (-4150 3250);
DISPLAY INVISIBLE (-4150 3250);
FORCEPROP 2 LAST CDS_LOCATION R8G2
J 0
(-4105 3375);
DISPLAY 0.617021 (-4105 3375);
PAINT AQUA (-4105 3375);
DISPLAY INVISIBLE (-4105 3375);
FORCEPROP 2 LAST SEC_TYPE 0402
J 0
(-4100 3475);
DISPLAY 1.021277 (-4100 3475);
PAINT ORANGE (-4100 3475);
DISPLAY INVISIBLE (-4100 3475);
FORCEPROP 2 LAST BOM_COST SM_CONTROLLER
J 0
(-4100 3475);
DISPLAY 1.021277 (-4100 3475);
PAINT ORANGE (-4100 3475);
DISPLAY INVISIBLE (-4100 3475);
FORCEPROP 2 LAST SEC 1
J 0
(-4100 3475);
PAINT MONO (-4100 3475);
DISPLAY INVISIBLE (-4100 3475);
FORCEPROP 2 LAST ROOM BMC_MISC
J 0
(-4100 3425);
DISPLAY 1.021277 (-4100 3425);
PAINT ORANGE (-4100 3425);
DISPLAY INVISIBLE (-4100 3425);
FORCEPROP 1 LAST PATH I267
J 0
(-4100 3425);
DISPLAY 0.978723 (-4100 3425);
PAINT WHITE (-4100 3425);
DISPLAY INVISIBLE (-4100 3425);
FORCEADD OFFPAGE..1
(-4625 3000);
FORCEPROP 2 LAST $XR0 119 
J 0
(-4877 3000);
DISPLAY 0.638298 (-4877 3000);
PAINT MONO (-4877 3000);
FORCEPROP 1 LAST COMMENT_BODY TRUE
J 0
(-4500 2900);
DISPLAY 0.872340 (-4500 2900);
PAINT GREEN (-4500 2900);
DISPLAY INVISIBLE (-4500 2900);
FORCEPROP 1 LAST OFFPAGE TRUE
J 0
(-4300 2875);
DISPLAY 0.872340 (-4300 2875);
PAINT GREEN (-4300 2875);
DISPLAY INVISIBLE (-4300 2875);
FORCEPROP 2 LAST CDS_LIB mstr_standard
J 0
(-4625 3000);
PAINT ORANGE (-4625 3000);
DISPLAY INVISIBLE (-4625 3000);
FORCEPROP 2 LAST PATH I270
J 0
(-4875 3050);
DISPLAY 1.021277 (-4875 3050);
PAINT ORANGE (-4875 3050);
DISPLAY INVISIBLE (-4875 3050);
FORCEADD OFFPAGE..1
(-4625 2900);
FORCEPROP 2 LAST $XR0 119 
J 0
(-4877 2900);
DISPLAY 0.638298 (-4877 2900);
PAINT MONO (-4877 2900);
FORCEPROP 2 LAST PATH I271
J 0
(-4875 2950);
DISPLAY 1.021277 (-4875 2950);
PAINT ORANGE (-4875 2950);
DISPLAY INVISIBLE (-4875 2950);
FORCEPROP 2 LAST CDS_LIB mstr_standard
J 0
(-4625 2900);
PAINT ORANGE (-4625 2900);
DISPLAY INVISIBLE (-4625 2900);
FORCEPROP 1 LAST OFFPAGE TRUE
J 0
(-4300 2775);
DISPLAY 0.872340 (-4300 2775);
PAINT GREEN (-4300 2775);
DISPLAY INVISIBLE (-4300 2775);
FORCEPROP 1 LAST COMMENT_BODY TRUE
J 0
(-4500 2800);
DISPLAY 0.872340 (-4500 2800);
PAINT GREEN (-4500 2800);
DISPLAY INVISIBLE (-4500 2800);
FORCEADD P3V3_STBY..1
(-3200 3700);
FORCEPROP 3 LASTPIN (-3200 3650) SIG_NAME P3V3_STBY\g
J 0
(-3190 3660);
DISPLAY 0.659574 (-3190 3660);
PAINT MONO (-3190 3660);
DISPLAY INVISIBLE (-3190 3660);
FORCEPROP 1 LAST VOLTAGE 3.3V
J 0
(-3245 3657);
DISPLAY 0.340426 (-3245 3657);
PAINT SKYBLUE (-3245 3657);
DISPLAY INVISIBLE (-3245 3657);
FORCEPROP 2 LAST CDS_LIB mstr_symbols
J 0
(-3200 3700);
PAINT ORANGE (-3200 3700);
DISPLAY INVISIBLE (-3200 3700);
FORCEPROP 1 LAST PATH I272
J 0
(-3155 3702);
DISPLAY 0.340426 (-3155 3702);
PAINT GREEN (-3155 3702);
DISPLAY INVISIBLE (-3155 3702);
FORCEPROP 1 LAST SIZE 1B
J 0
(-3155 3722);
DISPLAY 0.340426 (-3155 3722);
PAINT GREEN (-3155 3722);
DISPLAY INVISIBLE (-3155 3722);
FORCEPROP 1 LAST BODY_TYPE PLUMBING
J 0
(-3245 3657);
DISPLAY 0.340426 (-3245 3657);
PAINT GREEN (-3245 3657);
DISPLAY INVISIBLE (-3245 3657);
FORCEPROP 1 LAST HDL_POWER P3V3_STBY
J 0
(-3500 3575);
DISPLAY 0.872340 (-3500 3575);
PAINT ORANGE (-3500 3575);
DISPLAY INVISIBLE (-3500 3575);
FORCEADD CAP_A..1
(-3200 3450);
FORCEPROP 1 LASTPIN (-3200 3550) $PN 1
J 0
(-3190 3530);
DISPLAY 0.617021 (-3190 3530);
PAINT ORANGE (-3190 3530);
FORCEPROP 1 LAST PACK_TYPE 0402V
J 0
(-3150 3250);
DISPLAY 0.617021 (-3150 3250);
PAINT SKYBLUE (-3150 3250);
FORCEPROP 1 LAST VOLTAGE 16V
J 0
(-3150 3450);
DISPLAY 0.617021 (-3150 3450);
PAINT SKYBLUE (-3150 3450);
FORCEPROP 1 LAST VALUE 0.1UF
J 0
(-3150 3500);
DISPLAY 0.617021 (-3150 3500);
PAINT SKYBLUE (-3150 3500);
FORCEPROP 1 LAST LOCATION C2T35
J 0
(-3150 3550);
DISPLAY 0.617021 (-3150 3550);
PAINT AQUA (-3150 3550);
FORCEPROP 1 LAST PART_NUMBER A36096-030
J 0
(-3150 3300);
DISPLAY 0.617021 (-3150 3300);
PAINT BLUE (-3150 3300);
FORCEPROP 1 LAST TOLERANCE 10%
J 0
(-3150 3400);
DISPLAY 0.617021 (-3150 3400);
PAINT SKYBLUE (-3150 3400);
FORCEPROP 1 LAST MATERIAL X7R
J 0
(-3150 3350);
DISPLAY 0.617021 (-3150 3350);
PAINT SKYBLUE (-3150 3350);
FORCEPROP 1 LASTPIN (-3200 3350) $PN 2
J 0
(-3190 3330);
DISPLAY 0.617021 (-3190 3330);
PAINT ORANGE (-3190 3330);
FORCEPROP 2 LAST SEC_TYPE 0402V
J 0
(-3150 3650);
DISPLAY 1.021277 (-3150 3650);
PAINT ORANGE (-3150 3650);
DISPLAY INVISIBLE (-3150 3650);
FORCEPROP 2 LAST BOM_COST SM_CONTROLLER
J 0
(-3150 3650);
DISPLAY 1.021277 (-3150 3650);
PAINT ORANGE (-3150 3650);
DISPLAY INVISIBLE (-3150 3650);
FORCEPROP 2 LAST ROOM BMC_MISC
J 0
(-3150 3600);
DISPLAY 1.021277 (-3150 3600);
PAINT ORANGE (-3150 3600);
DISPLAY INVISIBLE (-3150 3600);
FORCEPROP 2 LAST SEC 1
J 0
(-3150 3600);
DISPLAY 0.680851 (-3150 3600);
PAINT MONO (-3150 3600);
DISPLAY INVISIBLE (-3150 3600);
FORCEPROP 2 LAST CDS_SEC 1
J 0
(-3150 3600);
PAINT ORANGE (-3150 3600);
DISPLAY INVISIBLE (-3150 3600);
FORCEPROP 1 LAST PATH I273
J 0
(-3150 3600);
DISPLAY 0.978723 (-3150 3600);
PAINT WHITE (-3150 3600);
DISPLAY INVISIBLE (-3150 3600);
FORCEPROP 2 LAST CDS_LOCATION C2T35
J 0
(-3150 3550);
DISPLAY 0.617021 (-3150 3550);
PAINT AQUA (-3150 3550);
DISPLAY INVISIBLE (-3150 3550);
FORCEPROP 2 LAST CDS_LIB dev_discrete
J 0
(-3200 3450);
PAINT ORANGE (-3200 3450);
DISPLAY INVISIBLE (-3200 3450);
FORCEADD GND..1
(-3200 3250);
FORCEPROP 3 LASTPIN (-3200 3300) SIG_NAME GND\g
J 0
(-3190 3310);
DISPLAY 0.659574 (-3190 3310);
PAINT MONO (-3190 3310);
DISPLAY INVISIBLE (-3190 3310);
FORCEPROP 1 LAST HDL_POWER GND
J 0
(-3200 3400);
DISPLAY 0.872340 (-3200 3400);
PAINT GREEN (-3200 3400);
DISPLAY INVISIBLE (-3200 3400);
FORCEPROP 1 LAST BODY_TYPE PLUMBING
J 0
(-3245 3207);
DISPLAY 0.340426 (-3245 3207);
PAINT GREEN (-3245 3207);
DISPLAY INVISIBLE (-3245 3207);
FORCEPROP 1 LAST VOLTAGE 0.0V
J 0
(-3245 3207);
DISPLAY 0.340426 (-3245 3207);
PAINT SKYBLUE (-3245 3207);
DISPLAY INVISIBLE (-3245 3207);
FORCEPROP 1 LAST PATH I274
J 0
(-3125 3250);
DISPLAY 0.872340 (-3125 3250);
PAINT AQUA (-3125 3250);
DISPLAY INVISIBLE (-3125 3250);
FORCEPROP 1 LAST SIZE 1B
J 0
(-3125 3200);
DISPLAY 0.872340 (-3125 3200);
PAINT AQUA (-3125 3200);
DISPLAY INVISIBLE (-3125 3200);
FORCEPROP 2 LAST CDS_LIB mstr_symbols
J 0
(-3200 3250);
PAINT ORANGE (-3200 3250);
DISPLAY INVISIBLE (-3200 3250);
FORCEADD CAP_A..1
(-3200 4600);
FORCEPROP 1 LAST VALUE 0.1UF
J 0
(-3150 4650);
DISPLAY 0.617021 (-3150 4650);
PAINT SKYBLUE (-3150 4650);
FORCEPROP 1 LAST LOCATION C8F16
J 0
(-3150 4700);
DISPLAY 0.617021 (-3150 4700);
PAINT AQUA (-3150 4700);
FORCEPROP 1 LASTPIN (-3200 4500) $PN 2
J 0
(-3190 4480);
DISPLAY 0.617021 (-3190 4480);
PAINT ORANGE (-3190 4480);
FORCEPROP 1 LAST MATERIAL X7R
J 0
(-3150 4500);
DISPLAY 0.617021 (-3150 4500);
PAINT SKYBLUE (-3150 4500);
FORCEPROP 1 LASTPIN (-3200 4700) $PN 1
J 0
(-3190 4680);
DISPLAY 0.617021 (-3190 4680);
PAINT ORANGE (-3190 4680);
FORCEPROP 1 LAST VOLTAGE 16V
J 0
(-3150 4600);
DISPLAY 0.617021 (-3150 4600);
PAINT SKYBLUE (-3150 4600);
FORCEPROP 1 LAST TOLERANCE 10%
J 0
(-3150 4550);
DISPLAY 0.617021 (-3150 4550);
PAINT SKYBLUE (-3150 4550);
FORCEPROP 1 LAST PART_NUMBER A36096-030
J 0
(-3150 4450);
DISPLAY 0.617021 (-3150 4450);
PAINT BLUE (-3150 4450);
FORCEPROP 1 LAST PACK_TYPE 0402V
J 0
(-3150 4400);
DISPLAY 0.617021 (-3150 4400);
PAINT SKYBLUE (-3150 4400);
FORCEPROP 2 LAST CDS_LOCATION C8F16
J 0
(-3150 4700);
DISPLAY 0.617021 (-3150 4700);
PAINT AQUA (-3150 4700);
DISPLAY INVISIBLE (-3150 4700);
FORCEPROP 2 LAST CDS_LIB dev_discrete
J 0
(-3200 4600);
PAINT ORANGE (-3200 4600);
DISPLAY INVISIBLE (-3200 4600);
FORCEPROP 1 LAST PATH I275
J 0
(-3150 4750);
DISPLAY 0.978723 (-3150 4750);
PAINT WHITE (-3150 4750);
DISPLAY INVISIBLE (-3150 4750);
FORCEPROP 2 LAST CDS_SEC 1
J 0
(-3150 4750);
PAINT ORANGE (-3150 4750);
DISPLAY INVISIBLE (-3150 4750);
FORCEPROP 2 LAST SEC 1
J 0
(-3150 4750);
DISPLAY 0.680851 (-3150 4750);
PAINT MONO (-3150 4750);
DISPLAY INVISIBLE (-3150 4750);
FORCEPROP 2 LAST ROOM BMC_MISC
J 0
(-3150 4750);
DISPLAY 1.021277 (-3150 4750);
PAINT ORANGE (-3150 4750);
DISPLAY INVISIBLE (-3150 4750);
FORCEPROP 2 LAST BOM_COST SM_CONTROLLER
J 0
(-3150 4800);
DISPLAY 1.021277 (-3150 4800);
PAINT ORANGE (-3150 4800);
DISPLAY INVISIBLE (-3150 4800);
FORCEPROP 2 LAST SEC_TYPE 0402V
J 0
(-3150 4800);
DISPLAY 1.021277 (-3150 4800);
PAINT ORANGE (-3150 4800);
DISPLAY INVISIBLE (-3150 4800);
FORCEADD GND..1
(-3200 4400);
FORCEPROP 3 LASTPIN (-3200 4450) SIG_NAME GND\g
J 0
(-3190 4460);
DISPLAY 0.659574 (-3190 4460);
PAINT MONO (-3190 4460);
DISPLAY INVISIBLE (-3190 4460);
FORCEPROP 1 LAST VOLTAGE 0.0V
J 0
(-3245 4357);
DISPLAY 0.340426 (-3245 4357);
PAINT SKYBLUE (-3245 4357);
DISPLAY INVISIBLE (-3245 4357);
FORCEPROP 2 LAST CDS_LIB mstr_symbols
J 0
(-3200 4400);
PAINT ORANGE (-3200 4400);
DISPLAY INVISIBLE (-3200 4400);
FORCEPROP 1 LAST PATH I276
J 0
(-3125 4400);
DISPLAY 0.872340 (-3125 4400);
PAINT AQUA (-3125 4400);
DISPLAY INVISIBLE (-3125 4400);
FORCEPROP 1 LAST SIZE 1B
J 0
(-3125 4350);
DISPLAY 0.872340 (-3125 4350);
PAINT AQUA (-3125 4350);
DISPLAY INVISIBLE (-3125 4350);
FORCEPROP 1 LAST BODY_TYPE PLUMBING
J 0
(-3245 4357);
DISPLAY 0.340426 (-3245 4357);
PAINT GREEN (-3245 4357);
DISPLAY INVISIBLE (-3245 4357);
FORCEPROP 1 LAST HDL_POWER GND
J 0
(-3200 4550);
DISPLAY 0.872340 (-3200 4550);
PAINT GREEN (-3200 4550);
DISPLAY INVISIBLE (-3200 4550);
FORCEADD P3V3_STBY..1
(-3200 4850);
FORCEPROP 3 LASTPIN (-3200 4800) SIG_NAME P3V3_STBY\g
J 0
(-3190 4810);
DISPLAY 0.659574 (-3190 4810);
PAINT MONO (-3190 4810);
DISPLAY INVISIBLE (-3190 4810);
FORCEPROP 2 LAST CDS_LIB mstr_symbols
J 0
(-3200 4850);
PAINT ORANGE (-3200 4850);
DISPLAY INVISIBLE (-3200 4850);
FORCEPROP 1 LAST SIZE 1B
J 0
(-3155 4872);
DISPLAY 0.340426 (-3155 4872);
PAINT GREEN (-3155 4872);
DISPLAY INVISIBLE (-3155 4872);
FORCEPROP 1 LAST PATH I277
J 0
(-3155 4852);
DISPLAY 0.340426 (-3155 4852);
PAINT GREEN (-3155 4852);
DISPLAY INVISIBLE (-3155 4852);
FORCEPROP 1 LAST VOLTAGE 3.3V
J 0
(-3245 4807);
DISPLAY 0.340426 (-3245 4807);
PAINT SKYBLUE (-3245 4807);
DISPLAY INVISIBLE (-3245 4807);
FORCEPROP 1 LAST BODY_TYPE PLUMBING
J 0
(-3245 4807);
DISPLAY 0.340426 (-3245 4807);
PAINT GREEN (-3245 4807);
DISPLAY INVISIBLE (-3245 4807);
FORCEPROP 1 LAST HDL_POWER P3V3_STBY
J 0
(-3500 4725);
DISPLAY 0.872340 (-3500 4725);
PAINT ORANGE (-3500 4725);
DISPLAY INVISIBLE (-3500 4725);
FORCEADD OFFPAGE..2
(-5850 2350);
FORCEPROP 2 LAST $XR3 120 
J 0
(-5331 2350);
DISPLAY 0.638298 (-5331 2350);
PAINT MONO (-5331 2350);
FORCEPROP 2 LAST $XR2 191 
J 0
(-5451 2350);
DISPLAY 0.638298 (-5451 2350);
PAINT MONO (-5451 2350);
FORCEPROP 2 LAST $XR1 157 
J 0
(-5571 2350);
DISPLAY 0.638298 (-5571 2350);
PAINT MONO (-5571 2350);
FORCEPROP 2 LAST $XR0 89 
J 0
(-5661 2350);
DISPLAY 0.638298 (-5661 2350);
PAINT MONO (-5661 2350);
FORCEPROP 2 LAST CDS_LIB mstr_standard
J 0
(-5850 2350);
PAINT MONO (-5850 2350);
DISPLAY INVISIBLE (-5850 2350);
FORCEPROP 2 LAST PATH I278
J 0
(-5325 2400);
DISPLAY 1.021277 (-5325 2400);
PAINT ORANGE (-5325 2400);
DISPLAY INVISIBLE (-5325 2400);
FORCEPROP 1 LAST OFFPAGE TRUE
J 0
(-5525 2225);
DISPLAY 0.872340 (-5525 2225);
PAINT GREEN (-5525 2225);
DISPLAY INVISIBLE (-5525 2225);
FORCEPROP 1 LAST COMMENT_BODY TRUE
J 0
(-5895 2255);
DISPLAY 0.872340 (-5895 2255);
PAINT GREEN (-5895 2255);
DISPLAY INVISIBLE (-5895 2255);
FORCEADD RES..1
(-6600 2350);
FORCEPROP 1 LAST MATERIAL EMPTY
J 0
(-6600 2200);
DISPLAY 0.617021 (-6600 2200);
PAINT RED (-6600 2200);
FORCEPROP 1 LAST WATTAGE 1/16W
J 2
(-6625 2200);
DISPLAY 0.617021 (-6625 2200);
PAINT SKYBLUE (-6625 2200);
FORCEPROP 1 LAST VALUE 0.0
J 2
(-6625 2250);
DISPLAY 0.617021 (-6625 2250);
PAINT SKYBLUE (-6625 2250);
FORCEPROP 1 LAST LOCATION R8E11
J 0
(-6650 2400);
DISPLAY 0.617021 (-6650 2400);
PAINT AQUA (-6650 2400);
FORCEPROP 1 LAST PART_NUMBER G21497-005
J 0
(-6650 2450);
DISPLAY 0.617021 (-6650 2450);
PAINT BLUE (-6650 2450);
FORCEPROP 1 LAST PACK_TYPE 0402
J 0
(-6350 2200);
DISPLAY 0.617021 (-6350 2200);
PAINT SKYBLUE (-6350 2200);
FORCEPROP 1 LAST TOLERANCE 5%
J 0
(-6600 2250);
DISPLAY 0.617021 (-6600 2250);
PAINT SKYBLUE (-6600 2250);
FORCEPROP 1 LASTPIN (-6700 2350) $PN 1
J 0
(-6688 2362);
DISPLAY 0.617021 (-6688 2362);
PAINT ORANGE (-6688 2362);
FORCEPROP 1 LASTPIN (-6500 2350) $PN 2
J 0
(-6538 2362);
DISPLAY 0.617021 (-6538 2362);
PAINT ORANGE (-6538 2362);
FORCEPROP 2 LAST CDS_LIB mstr_discrete
J 0
(-6600 2350);
PAINT MONO (-6600 2350);
DISPLAY INVISIBLE (-6600 2350);
FORCEPROP 2 LAST CDS_LOCATION R8E11
J 0
(-6650 2400);
DISPLAY 0.617021 (-6650 2400);
PAINT AQUA (-6650 2400);
DISPLAY INVISIBLE (-6650 2400);
FORCEPROP 1 LAST PATH I279
J 0
(-6650 2500);
DISPLAY 0.978723 (-6650 2500);
PAINT WHITE (-6650 2500);
DISPLAY INVISIBLE (-6650 2500);
FORCEPROP 2 LAST SEC_TYPE 0402
J 0
(-6650 2550);
DISPLAY 1.021277 (-6650 2550);
PAINT ORANGE (-6650 2550);
DISPLAY INVISIBLE (-6650 2550);
FORCEPROP 2 LAST SEC 1
J 0
(-6650 2550);
PAINT MONO (-6650 2550);
DISPLAY INVISIBLE (-6650 2550);
FORCEPROP 0 LAST ROOM BMC_MISC
J 0
(-6650 2550);
DISPLAY 1.021277 (-6650 2550);
PAINT ORANGE (-6650 2550);
DISPLAY INVISIBLE (-6650 2550);
FORCEPROP 0 LAST BOM_COST SM_CONTROLLER
J 0
(-6650 2650);
DISPLAY 1.021277 (-6650 2650);
PAINT ORANGE (-6650 2650);
DISPLAY INVISIBLE (-6650 2650);
FORCEADD OFFPAGE..1
(-7450 2350);
FORCEPROP 2 LAST $XR1 191 
J 0
(-7821 2350);
DISPLAY 0.638298 (-7821 2350);
PAINT MONO (-7821 2350);
FORCEPROP 2 LAST $XR0 94 
J 0
(-7701 2350);
DISPLAY 0.638298 (-7701 2350);
PAINT MONO (-7701 2350);
FORCEPROP 2 LAST PATH I280
J 0
(-7650 2400);
DISPLAY 1.021277 (-7650 2400);
PAINT ORANGE (-7650 2400);
DISPLAY INVISIBLE (-7650 2400);
FORCEPROP 2 LAST CDS_LIB mstr_standard
J 0
(-7450 2350);
PAINT MONO (-7450 2350);
DISPLAY INVISIBLE (-7450 2350);
FORCEPROP 1 LAST OFFPAGE TRUE
J 0
(-7125 2225);
DISPLAY 0.872340 (-7125 2225);
PAINT GREEN (-7125 2225);
DISPLAY INVISIBLE (-7125 2225);
FORCEPROP 1 LAST COMMENT_BODY TRUE
J 0
(-7325 2250);
DISPLAY 0.872340 (-7325 2250);
PAINT GREEN (-7325 2250);
DISPLAY INVISIBLE (-7325 2250);
FORCEADD CONN3_C95678002..1
(-7575 3700);
FORCEPROP 0 LAST CONFIG 021.60545.0103
J 0
(-7625 3475);
DISPLAY 0.638298 (-7625 3475);
PAINT BROWN (-7625 3475);
DISPLAY BOTH (-7625 3475);
FORCEPROP 1 LAST LOCATION J9B2
J 0
(-7625 3900);
DISPLAY 0.617021 (-7625 3900);
PAINT AQUA (-7625 3900);
FORCEPROP 2 LASTPIN (-7475 3750) $PN 1
J 0
(-7465 3760);
DISPLAY 0.617021 (-7465 3760);
PAINT ORANGE (-7465 3760);
FORCEPROP 1 LAST PART_NUMBER C95678-002
J 0
(-7625 3525);
DISPLAY 0.617021 (-7625 3525);
PAINT BLUE (-7625 3525);
FORCEPROP 1 LAST MATERIAL CONN
J 0
(-7625 3850);
DISPLAY 0.617021 (-7625 3850);
PAINT SKYBLUE (-7625 3850);
FORCEPROP 2 LASTPIN (-7475 3650) $PN 3
J 0
(-7465 3660);
DISPLAY 0.617021 (-7465 3660);
PAINT ORANGE (-7465 3660);
FORCEPROP 2 LASTPIN (-7475 3700) $PN 2
J 0
(-7465 3710);
DISPLAY 0.617021 (-7465 3710);
PAINT ORANGE (-7465 3710);
FORCEPROP 2 LAST CDS_LIB mstr_conn
J 0
(-7575 3700);
PAINT ORANGE (-7575 3700);
DISPLAY INVISIBLE (-7575 3700);
FORCEPROP 2 LAST SEC_TYPE PIP
J 0
(-7625 3950);
DISPLAY 1.021277 (-7625 3950);
PAINT ORANGE (-7625 3950);
DISPLAY INVISIBLE (-7625 3950);
FORCEPROP 2 LAST SEC 1
J 0
(-7625 3950);
DISPLAY 0.680851 (-7625 3950);
PAINT MONO (-7625 3950);
DISPLAY INVISIBLE (-7625 3950);
FORCEPROP 2 LAST CDS_LOCATION J9B2
J 0
(-7625 3900);
DISPLAY 0.617021 (-7625 3900);
PAINT AQUA (-7625 3900);
DISPLAY INVISIBLE (-7625 3900);
FORCEPROP 0 LAST ROOM DEBUG
J 0
(-7625 4000);
DISPLAY 1.021277 (-7625 4000);
PAINT ORANGE (-7625 4000);
DISPLAY INVISIBLE (-7625 4000);
FORCEPROP 1 LAST PACK_TYPE PIP
J 0
(-7625 3950);
DISPLAY 0.978723 (-7625 3950);
PAINT SKYBLUE (-7625 3950);
DISPLAY INVISIBLE (-7625 3950);
FORCEPROP 1 LAST PATH I281
J 0
(-7175 3850);
DISPLAY 0.978723 (-7175 3850);
PAINT BLUE (-7175 3850);
DISPLAY INVISIBLE (-7175 3850);
FORCEPROP 0 LAST BOM_COST DEBUG
J 0
(-7625 4100);
DISPLAY 1.021277 (-7625 4100);
PAINT ORANGE (-7625 4100);
DISPLAY INVISIBLE (-7625 4100);
FORCEADD GND..1
(-7275 3550);
FORCEPROP 3 LASTPIN (-7275 3600) SIG_NAME GND\g
J 0
(-7265 3610);
DISPLAY 0.659574 (-7265 3610);
PAINT MONO (-7265 3610);
DISPLAY INVISIBLE (-7265 3610);
FORCEPROP 1 LAST HDL_POWER GND
J 0
(-7275 3700);
DISPLAY 0.872340 (-7275 3700);
PAINT GREEN (-7275 3700);
DISPLAY INVISIBLE (-7275 3700);
FORCEPROP 1 LAST BODY_TYPE PLUMBING
J 0
(-7320 3507);
DISPLAY 0.340426 (-7320 3507);
PAINT GREEN (-7320 3507);
DISPLAY INVISIBLE (-7320 3507);
FORCEPROP 1 LAST VOLTAGE 0.0V
J 0
(-7320 3507);
DISPLAY 0.340426 (-7320 3507);
PAINT SKYBLUE (-7320 3507);
DISPLAY INVISIBLE (-7320 3507);
FORCEPROP 1 LAST PATH I282
J 0
(-7200 3550);
DISPLAY 0.872340 (-7200 3550);
PAINT AQUA (-7200 3550);
DISPLAY INVISIBLE (-7200 3550);
FORCEPROP 1 LAST SIZE 1B
J 0
(-7200 3500);
DISPLAY 0.872340 (-7200 3500);
PAINT AQUA (-7200 3500);
DISPLAY INVISIBLE (-7200 3500);
FORCEPROP 2 LAST CDS_LIB mstr_symbols
J 0
(-7275 3550);
PAINT ORANGE (-7275 3550);
DISPLAY INVISIBLE (-7275 3550);
FORCEADD OFFPAGE..3
(-6500 3750);
FORCEPROP 2 LAST $XR1 159 
J 0
(-6166 3750);
DISPLAY 0.638298 (-6166 3750);
PAINT MONO (-6166 3750);
FORCEPROP 2 LAST $XR0 138 
J 0
(-6286 3750);
DISPLAY 0.638298 (-6286 3750);
PAINT MONO (-6286 3750);
FORCEPROP 2 LAST CDS_LIB mstr_standard
J 0
(-6500 3750);
PAINT ORANGE (-6500 3750);
DISPLAY INVISIBLE (-6500 3750);
FORCEPROP 2 LAST PATH I283
J 0
(-6325 3825);
DISPLAY 1.021277 (-6325 3825);
PAINT ORANGE (-6325 3825);
DISPLAY INVISIBLE (-6325 3825);
FORCEPROP 1 LAST OFFPAGE TRUE
J 0
(-6175 3625);
DISPLAY 0.872340 (-6175 3625);
PAINT GREEN (-6175 3625);
DISPLAY INVISIBLE (-6175 3625);
FORCEPROP 1 LAST COMMENT_BODY TRUE
J 0
(-6550 3650);
DISPLAY 0.872340 (-6550 3650);
PAINT GREEN (-6550 3650);
DISPLAY INVISIBLE (-6550 3650);
FORCEADD OFFPAGE..4
(-6500 3650);
FORCEPROP 2 LAST $XR1 159 
J 0
(-6194 3650);
DISPLAY 0.638298 (-6194 3650);
PAINT MONO (-6194 3650);
FORCEPROP 2 LAST $XR0 138 
J 0
(-6314 3650);
DISPLAY 0.638298 (-6314 3650);
PAINT MONO (-6314 3650);
FORCEPROP 2 LAST CDS_LIB mstr_standard
J 0
(-6500 3650);
PAINT ORANGE (-6500 3650);
DISPLAY INVISIBLE (-6500 3650);
FORCEPROP 2 LAST PATH I284
J 0
(-6325 3725);
DISPLAY 1.021277 (-6325 3725);
PAINT ORANGE (-6325 3725);
DISPLAY INVISIBLE (-6325 3725);
FORCEPROP 1 LAST OFFPAGE TRUE
J 0
(-6175 3525);
DISPLAY 0.872340 (-6175 3525);
PAINT GREEN (-6175 3525);
DISPLAY INVISIBLE (-6175 3525);
FORCEPROP 1 LAST COMMENT_BODY TRUE
J 0
(-6525 3550);
DISPLAY 0.872340 (-6525 3550);
PAINT GREEN (-6525 3550);
DISPLAY INVISIBLE (-6525 3550);
FORCEADD CONN3_C95678002..1
(-7600 4475);
FORCEPROP 1 LAST LOCATION J8C1
J 0
(-7650 4675);
DISPLAY 0.617021 (-7650 4675);
PAINT AQUA (-7650 4675);
FORCEPROP 2 LASTPIN (-7500 4425) $PN 3
J 0
(-7490 4435);
DISPLAY 0.617021 (-7490 4435);
PAINT ORANGE (-7490 4435);
FORCEPROP 2 LASTPIN (-7500 4475) $PN 2
J 0
(-7490 4485);
DISPLAY 0.617021 (-7490 4485);
PAINT ORANGE (-7490 4485);
FORCEPROP 1 LAST MATERIAL CONN
J 0
(-7650 4625);
DISPLAY 0.617021 (-7650 4625);
PAINT SKYBLUE (-7650 4625);
FORCEPROP 2 LASTPIN (-7500 4525) $PN 1
J 0
(-7490 4535);
DISPLAY 0.617021 (-7490 4535);
PAINT ORANGE (-7490 4535);
FORCEPROP 1 LAST PART_NUMBER C95678-002
J 0
(-7650 4300);
DISPLAY 0.617021 (-7650 4300);
PAINT BLUE (-7650 4300);
FORCEPROP 0 LAST CONFIG 021.60545.0103
J 0
(-7650 4250);
DISPLAY 0.638298 (-7650 4250);
PAINT BROWN (-7650 4250);
DISPLAY BOTH (-7650 4250);
FORCEPROP 2 LAST CDS_LIB mstr_conn
J 0
(-7600 4475);
PAINT ORANGE (-7600 4475);
DISPLAY INVISIBLE (-7600 4475);
FORCEPROP 2 LAST SEC_TYPE PIP
J 0
(-7650 4725);
DISPLAY 1.021277 (-7650 4725);
PAINT ORANGE (-7650 4725);
DISPLAY INVISIBLE (-7650 4725);
FORCEPROP 0 LAST BOM_COST DEBUG
J 0
(-7650 4875);
DISPLAY 1.021277 (-7650 4875);
PAINT ORANGE (-7650 4875);
DISPLAY INVISIBLE (-7650 4875);
FORCEPROP 2 LAST SEC 1
J 0
(-7650 4725);
DISPLAY 0.680851 (-7650 4725);
PAINT MONO (-7650 4725);
DISPLAY INVISIBLE (-7650 4725);
FORCEPROP 2 LAST CDS_LOCATION J8C1
J 0
(-7650 4675);
DISPLAY 0.617021 (-7650 4675);
PAINT AQUA (-7650 4675);
DISPLAY INVISIBLE (-7650 4675);
FORCEPROP 1 LAST PATH I285
J 0
(-7200 4625);
DISPLAY 0.978723 (-7200 4625);
PAINT BLUE (-7200 4625);
DISPLAY INVISIBLE (-7200 4625);
FORCEPROP 0 LAST ROOM DEBUG
J 0
(-7650 4775);
DISPLAY 1.021277 (-7650 4775);
PAINT ORANGE (-7650 4775);
DISPLAY INVISIBLE (-7650 4775);
FORCEPROP 1 LAST PACK_TYPE PIP
J 0
(-7650 4725);
DISPLAY 0.978723 (-7650 4725);
PAINT SKYBLUE (-7650 4725);
DISPLAY INVISIBLE (-7650 4725);
FORCEADD OFFPAGE..4
(-6525 4425);
FORCEPROP 2 LAST $XR5 247 
J 0
(-5739 4425);
DISPLAY 0.638298 (-5739 4425);
PAINT MONO (-5739 4425);
FORCEPROP 2 LAST $XR4 111 
J 0
(-5859 4425);
DISPLAY 0.638298 (-5859 4425);
PAINT MONO (-5859 4425);
FORCEPROP 2 LAST $XR3 102 
J 0
(-5979 4425);
DISPLAY 0.638298 (-5979 4425);
PAINT MONO (-5979 4425);
FORCEPROP 2 LAST $XR2 101 
J 0
(-6099 4425);
DISPLAY 0.638298 (-6099 4425);
PAINT MONO (-6099 4425);
FORCEPROP 2 LAST $XR1 159 
J 0
(-6219 4425);
DISPLAY 0.638298 (-6219 4425);
PAINT MONO (-6219 4425);
FORCEPROP 2 LAST $XR0 138 
J 0
(-6339 4425);
DISPLAY 0.638298 (-6339 4425);
PAINT MONO (-6339 4425);
FORCEPROP 2 LAST CDS_LIB mstr_standard
J 0
(-6525 4425);
PAINT ORANGE (-6525 4425);
DISPLAY INVISIBLE (-6525 4425);
FORCEPROP 2 LAST PATH I286
J 0
(-6350 4500);
DISPLAY 1.021277 (-6350 4500);
PAINT ORANGE (-6350 4500);
DISPLAY INVISIBLE (-6350 4500);
FORCEPROP 1 LAST OFFPAGE TRUE
J 0
(-6200 4300);
DISPLAY 0.872340 (-6200 4300);
PAINT GREEN (-6200 4300);
DISPLAY INVISIBLE (-6200 4300);
FORCEPROP 1 LAST COMMENT_BODY TRUE
J 0
(-6550 4325);
DISPLAY 0.872340 (-6550 4325);
PAINT GREEN (-6550 4325);
DISPLAY INVISIBLE (-6550 4325);
FORCEADD OFFPAGE..3
(-6525 4525);
FORCEPROP 2 LAST $XR5 247 
J 0
(-5711 4525);
DISPLAY 0.638298 (-5711 4525);
PAINT MONO (-5711 4525);
FORCEPROP 2 LAST $XR4 159 
J 0
(-5831 4525);
DISPLAY 0.638298 (-5831 4525);
PAINT MONO (-5831 4525);
FORCEPROP 2 LAST $XR3 138 
J 0
(-5951 4525);
DISPLAY 0.638298 (-5951 4525);
PAINT MONO (-5951 4525);
FORCEPROP 2 LAST $XR2 111 
J 0
(-6071 4525);
DISPLAY 0.638298 (-6071 4525);
PAINT MONO (-6071 4525);
FORCEPROP 2 LAST $XR1 102 
J 0
(-6191 4525);
DISPLAY 0.638298 (-6191 4525);
PAINT MONO (-6191 4525);
FORCEPROP 2 LAST $XR0 101 
J 0
(-6311 4525);
DISPLAY 0.638298 (-6311 4525);
PAINT MONO (-6311 4525);
FORCEPROP 2 LAST CDS_LIB mstr_standard
J 0
(-6525 4525);
PAINT ORANGE (-6525 4525);
DISPLAY INVISIBLE (-6525 4525);
FORCEPROP 2 LAST PATH I287
J 0
(-6325 4600);
DISPLAY 1.021277 (-6325 4600);
PAINT ORANGE (-6325 4600);
DISPLAY INVISIBLE (-6325 4600);
FORCEPROP 1 LAST OFFPAGE TRUE
J 0
(-6200 4400);
DISPLAY 0.872340 (-6200 4400);
PAINT GREEN (-6200 4400);
DISPLAY INVISIBLE (-6200 4400);
FORCEPROP 1 LAST COMMENT_BODY TRUE
J 0
(-6575 4425);
DISPLAY 0.872340 (-6575 4425);
PAINT GREEN (-6575 4425);
DISPLAY INVISIBLE (-6575 4425);
FORCEADD RES..1
(-1700 4200);
FORCEPROP 1 LASTPIN (-1600 4200) $PN 2
J 0
(-1638 4212);
DISPLAY 0.617021 (-1638 4212);
PAINT ORANGE (-1638 4212);
FORCEPROP 1 LASTPIN (-1800 4200) $PN 1
J 0
(-1788 4212);
DISPLAY 0.617021 (-1788 4212);
PAINT ORANGE (-1788 4212);
FORCEPROP 1 LAST VALUE 49.9
J 2
(-1875 4300);
DISPLAY 0.617021 (-1875 4300);
PAINT SKYBLUE (-1875 4300);
FORCEPROP 1 LAST TOLERANCE 1%
J 0
(-1850 4300);
DISPLAY 0.617021 (-1850 4300);
PAINT SKYBLUE (-1850 4300);
FORCEPROP 1 LAST PACK_TYPE 0402
J 0
(-1475 4300);
DISPLAY 0.617021 (-1475 4300);
PAINT SKYBLUE (-1475 4300);
FORCEPROP 1 LAST MATERIAL CHIP
J 0
(-1350 4300);
DISPLAY 0.617021 (-1350 4300);
PAINT SKYBLUE (-1350 4300);
FORCEPROP 1 LAST WATTAGE 1/16W
J 0
(-1575 4250);
DISPLAY 0.638298 (-1575 4250);
PAINT SKYBLUE (-1575 4250);
FORCEPROP 1 LAST PART_NUMBER G21796-047
J 0
(-1750 4300);
DISPLAY 0.617021 (-1750 4300);
PAINT BLUE (-1750 4300);
FORCEPROP 1 LAST LOCATION R2T18
J 0
(-1750 4250);
DISPLAY 0.617021 (-1750 4250);
PAINT AQUA (-1750 4250);
FORCEPROP 2 LAST CDS_LIB mstr_discrete
J 0
(-1700 4200);
PAINT ORANGE (-1700 4200);
DISPLAY INVISIBLE (-1700 4200);
FORCEPROP 1 LAST PATH I288
J 0
(-1750 4350);
DISPLAY 0.978723 (-1750 4350);
PAINT WHITE (-1750 4350);
DISPLAY INVISIBLE (-1750 4350);
FORCEPROP 2 LAST CDS_LOCATION R2T18
J 0
(-1750 4250);
DISPLAY 0.617021 (-1750 4250);
PAINT AQUA (-1750 4250);
DISPLAY INVISIBLE (-1750 4250);
FORCEPROP 2 LAST SEC 1
J 0
(-1750 4400);
PAINT MONO (-1750 4400);
DISPLAY INVISIBLE (-1750 4400);
FORCEPROP 2 LAST SEC_TYPE 0402
J 0
(-1750 4400);
DISPLAY 1.021277 (-1750 4400);
PAINT ORANGE (-1750 4400);
DISPLAY INVISIBLE (-1750 4400);
FORCEPROP 0 LAST BOM_COST SM_CONTROLLER
J 0
(-1350 4500);
DISPLAY 1.021277 (-1350 4500);
PAINT ORANGE (-1350 4500);
DISPLAY INVISIBLE (-1350 4500);
FORCEPROP 0 LAST ROOM BMC_MISC
J 0
(-1350 4400);
DISPLAY 1.021277 (-1350 4400);
PAINT ORANGE (-1350 4400);
DISPLAY INVISIBLE (-1350 4400);
FORCEADD RES..1
R 6
(-1700 4100);
FORCEPROP 1 LAST MATERIAL CHIP
J 0
(-1350 3971);
DISPLAY 0.617021 (-1350 3971);
PAINT SKYBLUE (-1350 3971);
FORCEPROP 1 LAST PACK_TYPE 0402
J 0
(-1475 3971);
DISPLAY 0.617021 (-1475 3971);
PAINT SKYBLUE (-1475 3971);
FORCEPROP 1 LASTPIN (-1600 4100) $PN 2
J 0
(-1638 4051);
DISPLAY 0.617021 (-1638 4051);
PAINT ORANGE (-1638 4051);
FORCEPROP 1 LAST TOLERANCE 1%
J 0
(-1850 3971);
DISPLAY 0.617021 (-1850 3971);
PAINT SKYBLUE (-1850 3971);
FORCEPROP 1 LASTPIN (-1800 4100) $PN 1
J 0
(-1788 4051);
DISPLAY 0.617021 (-1788 4051);
PAINT ORANGE (-1788 4051);
FORCEPROP 1 LAST LOCATION R2T28
J 0
(-1750 4021);
DISPLAY 0.617021 (-1750 4021);
PAINT AQUA (-1750 4021);
FORCEPROP 1 LAST WATTAGE 1/16W
J 0
(-1575 4029);
DISPLAY 0.638298 (-1575 4029);
PAINT SKYBLUE (-1575 4029);
FORCEPROP 1 LAST PART_NUMBER G21796-074
J 0
(-1750 3971);
DISPLAY 0.617021 (-1750 3971);
PAINT BLUE (-1750 3971);
FORCEPROP 1 LAST VALUE 33.2
J 2
(-1875 3971);
DISPLAY 0.617021 (-1875 3971);
PAINT SKYBLUE (-1875 3971);
FORCEPROP 2 LAST CDS_LIB mstr_discrete
J 0
(-1700 4053);
PAINT ORANGE (-1700 4053);
DISPLAY INVISIBLE (-1700 4053);
FORCEPROP 2 LAST SEC_TYPE 0402
J 0
(-1750 4050);
DISPLAY 1.021277 (-1750 4050);
PAINT ORANGE (-1750 4050);
DISPLAY INVISIBLE (-1750 4050);
FORCEPROP 2 LAST SEC 1
J 0
(-1750 4050);
PAINT MONO (-1750 4050);
DISPLAY INVISIBLE (-1750 4050);
FORCEPROP 2 LAST CDS_LOCATION R2T28
J 0
(-1750 4021);
DISPLAY 0.617021 (-1750 4021);
PAINT AQUA (-1750 4021);
DISPLAY INVISIBLE (-1750 4021);
FORCEPROP 1 LAST PATH I289
J 0
(-1750 3904);
DISPLAY 0.978723 (-1750 3904);
PAINT WHITE (-1750 3904);
DISPLAY INVISIBLE (-1750 3904);
FORCEPROP 0 LAST BOM_COST SM_CONTROLLER
J 0
(-1350 3752);
DISPLAY 1.021277 (-1350 3752);
PAINT ORANGE (-1350 3752);
DISPLAY INVISIBLE (-1350 3752);
FORCEPROP 0 LAST ROOM BMC_MISC
J 0
(-1350 3852);
DISPLAY 1.021277 (-1350 3852);
PAINT ORANGE (-1350 3852);
DISPLAY INVISIBLE (-1350 3852);
FORCEADD OFFPAGE..1
(-4075 1550);
FORCEPROP 2 LAST $XR1 164 
J 0
(-4477 1550);
DISPLAY 0.638298 (-4477 1550);
PAINT MONO (-4477 1550);
FORCEPROP 2 LAST $XR0 119 
J 0
(-4357 1550);
DISPLAY 0.638298 (-4357 1550);
PAINT MONO (-4357 1550);
FORCEPROP 2 LAST PATH I296
J 0
(-4025 1625);
DISPLAY 1.021277 (-4025 1625);
PAINT ORANGE (-4025 1625);
DISPLAY INVISIBLE (-4025 1625);
FORCEPROP 2 LAST CDS_LIB mstr_standard
J 0
(-4075 1550);
PAINT ORANGE (-4075 1550);
DISPLAY INVISIBLE (-4075 1550);
FORCEPROP 1 LAST OFFPAGE TRUE
J 0
(-3750 1425);
DISPLAY 0.872340 (-3750 1425);
PAINT GREEN (-3750 1425);
DISPLAY INVISIBLE (-3750 1425);
FORCEPROP 1 LAST COMMENT_BODY TRUE
J 0
(-3950 1450);
DISPLAY 0.872340 (-3950 1450);
PAINT GREEN (-3950 1450);
DISPLAY INVISIBLE (-3950 1450);
FORCEADD OFFPAGE..2
(-1825 1825);
FORCEPROP 2 LAST $XR1 21 
J 0
(-1546 1825);
DISPLAY 0.638298 (-1546 1825);
PAINT MONO (-1546 1825);
FORCEPROP 2 LAST $XR0 90 
J 0
(-1636 1825);
DISPLAY 0.638298 (-1636 1825);
PAINT MONO (-1636 1825);
FORCEPROP 2 LAST CDS_LIB mstr_standard
J 0
(-1825 1825);
PAINT ORANGE (-1825 1825);
DISPLAY INVISIBLE (-1825 1825);
FORCEPROP 2 LAST PATH I297
J 0
(-1775 1900);
DISPLAY 1.021277 (-1775 1900);
PAINT ORANGE (-1775 1900);
DISPLAY INVISIBLE (-1775 1900);
FORCEPROP 1 LAST OFFPAGE TRUE
J 0
(-1500 1700);
DISPLAY 0.872340 (-1500 1700);
PAINT GREEN (-1500 1700);
DISPLAY INVISIBLE (-1500 1700);
FORCEPROP 1 LAST COMMENT_BODY TRUE
J 0
(-1870 1730);
DISPLAY 0.872340 (-1870 1730);
PAINT GREEN (-1870 1730);
DISPLAY INVISIBLE (-1870 1730);
FORCEADD OFFPAGE..2
(-1825 1550);
FORCEPROP 2 LAST $XR1 55 
J 0
(-1546 1550);
DISPLAY 0.638298 (-1546 1550);
PAINT MONO (-1546 1550);
FORCEPROP 2 LAST $XR0 90 
J 0
(-1636 1550);
DISPLAY 0.638298 (-1636 1550);
PAINT MONO (-1636 1550);
FORCEPROP 2 LAST CDS_LIB mstr_standard
J 0
(-1825 1550);
PAINT ORANGE (-1825 1550);
DISPLAY INVISIBLE (-1825 1550);
FORCEPROP 2 LAST PATH I298
J 0
(-1775 1625);
DISPLAY 1.021277 (-1775 1625);
PAINT ORANGE (-1775 1625);
DISPLAY INVISIBLE (-1775 1625);
FORCEPROP 1 LAST OFFPAGE TRUE
J 0
(-1500 1425);
DISPLAY 0.872340 (-1500 1425);
PAINT GREEN (-1500 1425);
DISPLAY INVISIBLE (-1500 1425);
FORCEPROP 1 LAST COMMENT_BODY TRUE
J 0
(-1870 1455);
DISPLAY 0.872340 (-1870 1455);
PAINT GREEN (-1870 1455);
DISPLAY INVISIBLE (-1870 1455);
FORCEADD RES..1
(-2900 1825);
FORCEPROP 1 LASTPIN (-2800 1825) $PN 2
J 0
(-2838 1837);
DISPLAY 0.617021 (-2838 1837);
PAINT ORANGE (-2838 1837);
FORCEPROP 1 LASTPIN (-3000 1825) $PN 1
J 0
(-2988 1837);
DISPLAY 0.617021 (-2988 1837);
PAINT ORANGE (-2988 1837);
FORCEPROP 1 LAST LOCATION R6D16
J 0
(-3100 1925);
DISPLAY 0.617021 (-3100 1925);
PAINT AQUA (-3100 1925);
FORCEPROP 1 LAST VALUE 0.0
J 0
(-2900 1925);
DISPLAY 0.617021 (-2900 1925);
PAINT SKYBLUE (-2900 1925);
FORCEPROP 1 LAST TOLERANCE 5%
J 0
(-2800 1925);
DISPLAY 0.638298 (-2800 1925);
PAINT SKYBLUE (-2800 1925);
FORCEPROP 1 LAST PART_NUMBER G21497-005
J 0
(-2750 1850);
DISPLAY 0.617021 (-2750 1850);
PAINT BLUE (-2750 1850);
FORCEPROP 1 LAST WATTAGE 1/16W
J 0
(-2700 1925);
DISPLAY 0.638298 (-2700 1925);
PAINT SKYBLUE (-2700 1925);
FORCEPROP 1 LAST PACK_TYPE 0402
J 0
(-2450 1850);
DISPLAY 0.617021 (-2450 1850);
PAINT SKYBLUE (-2450 1850);
FORCEPROP 1 LAST MATERIAL EMPTY
J 0
(-3125 1850);
DISPLAY 0.617021 (-3125 1850);
PAINT RED (-3125 1850);
FORCEPROP 1 LAST PATH I299
J 0
(-2950 1975);
DISPLAY 0.978723 (-2950 1975);
PAINT WHITE (-2950 1975);
DISPLAY INVISIBLE (-2950 1975);
FORCEPROP 2 LAST CDS_LIB mstr_discrete
J 0
(-2900 1825);
PAINT ORANGE (-2900 1825);
DISPLAY INVISIBLE (-2900 1825);
FORCEPROP 0 LAST ROOM BMC_MISC
J 0
(-2800 1950);
DISPLAY 1.021277 (-2800 1950);
PAINT ORANGE (-2800 1950);
DISPLAY INVISIBLE (-2800 1950);
FORCEPROP 2 LAST SEC_TYPE 0402
J 0
(-2950 2025);
DISPLAY 1.021277 (-2950 2025);
PAINT ORANGE (-2950 2025);
DISPLAY INVISIBLE (-2950 2025);
FORCEPROP 2 LAST SEC 1
J 0
(-2950 2025);
DISPLAY 0.680851 (-2950 2025);
PAINT MONO (-2950 2025);
DISPLAY INVISIBLE (-2950 2025);
FORCEPROP 0 LAST BOM_COST SM_CONTROLLER
J 0
(-2800 2050);
DISPLAY 1.021277 (-2800 2050);
PAINT ORANGE (-2800 2050);
DISPLAY INVISIBLE (-2800 2050);
FORCEADD RES..1
(-2900 1550);
FORCEPROP 1 LAST VALUE 0.0
J 0
(-2900 1650);
DISPLAY 0.617021 (-2900 1650);
PAINT SKYBLUE (-2900 1650);
FORCEPROP 1 LASTPIN (-2800 1550) $PN 2
J 0
(-2838 1562);
DISPLAY 0.617021 (-2838 1562);
PAINT ORANGE (-2838 1562);
FORCEPROP 1 LAST WATTAGE 1/16W
J 0
(-2700 1650);
DISPLAY 0.638298 (-2700 1650);
PAINT SKYBLUE (-2700 1650);
FORCEPROP 1 LAST TOLERANCE 5%
J 0
(-2800 1650);
DISPLAY 0.638298 (-2800 1650);
PAINT SKYBLUE (-2800 1650);
FORCEPROP 1 LAST PACK_TYPE 0402
J 0
(-2450 1575);
DISPLAY 0.617021 (-2450 1575);
PAINT SKYBLUE (-2450 1575);
FORCEPROP 1 LAST PART_NUMBER G21497-005
J 0
(-2750 1575);
DISPLAY 0.617021 (-2750 1575);
PAINT BLUE (-2750 1575);
FORCEPROP 1 LASTPIN (-3000 1550) $PN 1
J 0
(-2988 1562);
DISPLAY 0.617021 (-2988 1562);
PAINT ORANGE (-2988 1562);
FORCEPROP 1 LAST LOCATION R3D31
J 0
(-3100 1650);
DISPLAY 0.617021 (-3100 1650);
PAINT AQUA (-3100 1650);
FORCEPROP 1 LAST MATERIAL EMPTY
J 0
(-3125 1575);
DISPLAY 0.617021 (-3125 1575);
PAINT RED (-3125 1575);
FORCEPROP 2 LAST SEC 1
J 0
(-2950 1750);
DISPLAY 0.680851 (-2950 1750);
PAINT MONO (-2950 1750);
DISPLAY INVISIBLE (-2950 1750);
FORCEPROP 1 LAST PATH I300
J 0
(-2950 1700);
DISPLAY 0.978723 (-2950 1700);
PAINT WHITE (-2950 1700);
DISPLAY INVISIBLE (-2950 1700);
FORCEPROP 2 LAST CDS_LIB mstr_discrete
J 0
(-2900 1550);
PAINT ORANGE (-2900 1550);
DISPLAY INVISIBLE (-2900 1550);
FORCEPROP 2 LAST SEC_TYPE 0402
J 0
(-2950 1750);
DISPLAY 1.021277 (-2950 1750);
PAINT ORANGE (-2950 1750);
DISPLAY INVISIBLE (-2950 1750);
FORCEPROP 0 LAST ROOM BMC_MISC
J 0
(-2800 1675);
DISPLAY 1.021277 (-2800 1675);
PAINT ORANGE (-2800 1675);
DISPLAY INVISIBLE (-2800 1675);
FORCEPROP 0 LAST BOM_COST SM_CONTROLLER
J 0
(-2800 1775);
DISPLAY 1.021277 (-2800 1775);
PAINT ORANGE (-2800 1775);
DISPLAY INVISIBLE (-2800 1775);
FORCEADD RES..1
(-4000 975);
FORCEPROP 1 LASTPIN (-4100 975) $PN 1
J 0
(-4088 987);
DISPLAY 0.617021 (-4088 987);
PAINT ORANGE (-4088 987);
FORCEPROP 1 LAST LOCATION R6N14
J 0
(-4200 1050);
DISPLAY 0.617021 (-4200 1050);
PAINT AQUA (-4200 1050);
FORCEPROP 1 LAST VALUE 1.00K
J 0
(-4000 1050);
DISPLAY 0.617021 (-4000 1050);
PAINT SKYBLUE (-4000 1050);
FORCEPROP 1 LASTPIN (-3900 975) $PN 2
J 0
(-3938 987);
DISPLAY 0.617021 (-3938 987);
PAINT ORANGE (-3938 987);
FORCEPROP 1 LAST TOLERANCE 1%
J 0
(-3850 1050);
DISPLAY 0.617021 (-3850 1050);
PAINT SKYBLUE (-3850 1050);
FORCEPROP 1 LAST MATERIAL CHIP
J 0
(-3600 1050);
DISPLAY 0.638298 (-3600 1050);
PAINT SKYBLUE (-3600 1050);
FORCEPROP 1 LAST WATTAGE 1/16W
J 0
(-3750 1050);
DISPLAY 0.617021 (-3750 1050);
PAINT SKYBLUE (-3750 1050);
FORCEPROP 1 LAST PART_NUMBER G21796-026
J 0
(-3450 1050);
DISPLAY 0.617021 (-3450 1050);
PAINT BLUE (-3450 1050);
FORCEPROP 1 LAST PACK_TYPE 0402
J 0
(-3200 1050);
DISPLAY 0.638298 (-3200 1050);
PAINT SKYBLUE (-3200 1050);
FORCEPROP 2 LAST CDS_LIB mstr_discrete
J 0
(-4000 975);
PAINT ORANGE (-4000 975);
DISPLAY INVISIBLE (-4000 975);
FORCEPROP 0 LAST ROOM CPU0
J 0
(-4050 1125);
DISPLAY 1.021277 (-4050 1125);
PAINT ORANGE (-4050 1125);
DISPLAY INVISIBLE (-4050 1125);
FORCEPROP 1 LAST PATH I302
J 0
(-4050 1125);
DISPLAY 0.978723 (-4050 1125);
PAINT WHITE (-4050 1125);
DISPLAY INVISIBLE (-4050 1125);
FORCEPROP 2 LAST SEC 1
J 0
(-4050 1175);
DISPLAY 0.680851 (-4050 1175);
PAINT MONO (-4050 1175);
DISPLAY INVISIBLE (-4050 1175);
FORCEPROP 2 LAST SEC_TYPE 0402
J 0
(-4050 1175);
DISPLAY 1.021277 (-4050 1175);
PAINT ORANGE (-4050 1175);
DISPLAY INVISIBLE (-4050 1175);
FORCEADD RES..1
(-4000 775);
FORCEPROP 1 LAST PACK_TYPE 0402
J 0
(-3200 825);
DISPLAY 0.638298 (-3200 825);
PAINT SKYBLUE (-3200 825);
FORCEPROP 1 LAST LOCATION R6N13
J 0
(-4200 825);
DISPLAY 0.617021 (-4200 825);
PAINT AQUA (-4200 825);
FORCEPROP 1 LASTPIN (-4100 775) $PN 1
J 0
(-4088 787);
DISPLAY 0.617021 (-4088 787);
PAINT ORANGE (-4088 787);
FORCEPROP 1 LAST PART_NUMBER G21796-026
J 0
(-3450 825);
DISPLAY 0.617021 (-3450 825);
PAINT BLUE (-3450 825);
FORCEPROP 1 LAST VALUE 1.00K
J 0
(-4000 825);
DISPLAY 0.617021 (-4000 825);
PAINT SKYBLUE (-4000 825);
FORCEPROP 1 LASTPIN (-3900 775) $PN 2
J 0
(-3938 787);
DISPLAY 0.617021 (-3938 787);
PAINT ORANGE (-3938 787);
FORCEPROP 1 LAST TOLERANCE 1%
J 0
(-3850 825);
DISPLAY 0.617021 (-3850 825);
PAINT SKYBLUE (-3850 825);
FORCEPROP 1 LAST WATTAGE 1/16W
J 0
(-3750 825);
DISPLAY 0.617021 (-3750 825);
PAINT SKYBLUE (-3750 825);
FORCEPROP 1 LAST MATERIAL CHIP
J 0
(-3600 825);
DISPLAY 0.638298 (-3600 825);
PAINT SKYBLUE (-3600 825);
FORCEPROP 2 LAST CDS_LIB mstr_discrete
J 0
(-4000 775);
PAINT ORANGE (-4000 775);
DISPLAY INVISIBLE (-4000 775);
FORCEPROP 0 LAST ROOM CPU0
J 0
(-4050 925);
DISPLAY 1.021277 (-4050 925);
PAINT ORANGE (-4050 925);
DISPLAY INVISIBLE (-4050 925);
FORCEPROP 1 LAST PATH I303
J 0
(-4050 925);
DISPLAY 0.978723 (-4050 925);
PAINT WHITE (-4050 925);
DISPLAY INVISIBLE (-4050 925);
FORCEPROP 2 LAST SEC 1
J 0
(-4050 975);
DISPLAY 0.680851 (-4050 975);
PAINT MONO (-4050 975);
DISPLAY INVISIBLE (-4050 975);
FORCEPROP 2 LAST SEC_TYPE 0402
J 0
(-4050 975);
DISPLAY 1.021277 (-4050 975);
PAINT ORANGE (-4050 975);
DISPLAY INVISIBLE (-4050 975);
FORCEADD RES..1
(-4000 575);
FORCEPROP 1 LAST TOLERANCE 1%
J 0
(-3850 625);
DISPLAY 0.617021 (-3850 625);
PAINT SKYBLUE (-3850 625);
FORCEPROP 1 LAST WATTAGE 1/16W
J 0
(-3750 625);
DISPLAY 0.617021 (-3750 625);
PAINT SKYBLUE (-3750 625);
FORCEPROP 1 LAST MATERIAL CHIP
J 0
(-3600 625);
DISPLAY 0.638298 (-3600 625);
PAINT SKYBLUE (-3600 625);
FORCEPROP 1 LAST PACK_TYPE 0402
J 0
(-3200 625);
DISPLAY 0.638298 (-3200 625);
PAINT SKYBLUE (-3200 625);
FORCEPROP 1 LAST PART_NUMBER G21796-026
J 0
(-3450 625);
DISPLAY 0.617021 (-3450 625);
PAINT BLUE (-3450 625);
FORCEPROP 1 LAST VALUE 1.00K
J 0
(-4000 625);
DISPLAY 0.617021 (-4000 625);
PAINT SKYBLUE (-4000 625);
FORCEPROP 1 LASTPIN (-3900 575) $PN 2
J 0
(-3938 587);
DISPLAY 0.617021 (-3938 587);
PAINT ORANGE (-3938 587);
FORCEPROP 1 LASTPIN (-4100 575) $PN 1
J 0
(-4088 587);
DISPLAY 0.617021 (-4088 587);
PAINT ORANGE (-4088 587);
FORCEPROP 1 LAST LOCATION R6N15
J 0
(-4200 625);
DISPLAY 0.617021 (-4200 625);
PAINT AQUA (-4200 625);
FORCEPROP 0 LAST ROOM CPU0
J 0
(-4050 725);
DISPLAY 1.021277 (-4050 725);
PAINT ORANGE (-4050 725);
DISPLAY INVISIBLE (-4050 725);
FORCEPROP 1 LAST PATH I304
J 0
(-4050 725);
DISPLAY 0.978723 (-4050 725);
PAINT WHITE (-4050 725);
DISPLAY INVISIBLE (-4050 725);
FORCEPROP 2 LAST CDS_LIB mstr_discrete
J 0
(-4000 575);
PAINT ORANGE (-4000 575);
DISPLAY INVISIBLE (-4000 575);
FORCEPROP 2 LAST SEC_TYPE 0402
J 0
(-4050 775);
DISPLAY 1.021277 (-4050 775);
PAINT ORANGE (-4050 775);
DISPLAY INVISIBLE (-4050 775);
FORCEPROP 2 LAST SEC 1
J 0
(-4050 775);
DISPLAY 0.680851 (-4050 775);
PAINT MONO (-4050 775);
DISPLAY INVISIBLE (-4050 775);
FORCEADD OFFPAGE..2
(-6550 1525);
FORCEPROP 2 LAST $XR0 21 
J 0
(-6361 1525);
DISPLAY 0.638298 (-6361 1525);
PAINT MONO (-6361 1525);
FORCEPROP 2 LAST CDS_LIB mstr_standard
J 0
(-6550 1525);
PAINT ORANGE (-6550 1525);
DISPLAY INVISIBLE (-6550 1525);
FORCEPROP 2 LAST PATH I305
J 0
(-6500 1600);
DISPLAY 1.021277 (-6500 1600);
PAINT ORANGE (-6500 1600);
DISPLAY INVISIBLE (-6500 1600);
FORCEPROP 1 LAST OFFPAGE TRUE
J 0
(-6225 1400);
DISPLAY 0.872340 (-6225 1400);
PAINT GREEN (-6225 1400);
DISPLAY INVISIBLE (-6225 1400);
FORCEPROP 1 LAST COMMENT_BODY TRUE
J 0
(-6595 1430);
DISPLAY 0.872340 (-6595 1430);
PAINT GREEN (-6595 1430);
DISPLAY INVISIBLE (-6595 1430);
FORCEADD GND..1
(-4275 425);
FORCEPROP 3 LASTPIN (-4275 475) SIG_NAME GND\g
J 0
(-4265 485);
DISPLAY 0.659574 (-4265 485);
PAINT MONO (-4265 485);
DISPLAY INVISIBLE (-4265 485);
FORCEPROP 2 LAST CDS_LIB mstr_symbols
J 0
(-4275 425);
PAINT ORANGE (-4275 425);
DISPLAY INVISIBLE (-4275 425);
FORCEPROP 1 LAST SIZE 1B
J 0
(-4200 375);
DISPLAY 0.872340 (-4200 375);
PAINT AQUA (-4200 375);
DISPLAY INVISIBLE (-4200 375);
FORCEPROP 1 LAST PATH I306
J 0
(-4200 425);
DISPLAY 0.872340 (-4200 425);
PAINT AQUA (-4200 425);
DISPLAY INVISIBLE (-4200 425);
FORCEPROP 1 LAST VOLTAGE 0.0V
J 0
(-4320 382);
DISPLAY 0.340426 (-4320 382);
PAINT SKYBLUE (-4320 382);
DISPLAY INVISIBLE (-4320 382);
FORCEPROP 1 LAST BODY_TYPE PLUMBING
J 0
(-4320 382);
DISPLAY 0.340426 (-4320 382);
PAINT GREEN (-4320 382);
DISPLAY INVISIBLE (-4320 382);
FORCEPROP 1 LAST HDL_POWER GND
J 0
(-4275 575);
DISPLAY 0.872340 (-4275 575);
PAINT GREEN (-4275 575);
DISPLAY INVISIBLE (-4275 575);
FORCEADD OFFPAGE..2
(-2950 975);
FORCEPROP 2 LAST $XR0 21 
J 0
(-2761 975);
DISPLAY 0.638298 (-2761 975);
PAINT MONO (-2761 975);
FORCEPROP 2 LAST CDS_LIB mstr_standard
J 0
(-2950 975);
PAINT ORANGE (-2950 975);
DISPLAY INVISIBLE (-2950 975);
FORCEPROP 2 LAST PATH I308
J 0
(-2775 1050);
DISPLAY 1.021277 (-2775 1050);
PAINT ORANGE (-2775 1050);
DISPLAY INVISIBLE (-2775 1050);
FORCEPROP 1 LAST OFFPAGE TRUE
J 0
(-2625 850);
DISPLAY 0.872340 (-2625 850);
PAINT GREEN (-2625 850);
DISPLAY INVISIBLE (-2625 850);
FORCEPROP 1 LAST COMMENT_BODY TRUE
J 0
(-2995 880);
DISPLAY 0.872340 (-2995 880);
PAINT GREEN (-2995 880);
DISPLAY INVISIBLE (-2995 880);
FORCEADD OFFPAGE..2
(-2950 775);
FORCEPROP 2 LAST $XR0 21 
J 0
(-2761 775);
DISPLAY 0.638298 (-2761 775);
PAINT MONO (-2761 775);
FORCEPROP 2 LAST CDS_LIB mstr_standard
J 0
(-2950 775);
PAINT ORANGE (-2950 775);
DISPLAY INVISIBLE (-2950 775);
FORCEPROP 2 LAST PATH I309
J 0
(-2775 850);
DISPLAY 1.021277 (-2775 850);
PAINT ORANGE (-2775 850);
DISPLAY INVISIBLE (-2775 850);
FORCEPROP 1 LAST OFFPAGE TRUE
J 0
(-2625 650);
DISPLAY 0.872340 (-2625 650);
PAINT GREEN (-2625 650);
DISPLAY INVISIBLE (-2625 650);
FORCEPROP 1 LAST COMMENT_BODY TRUE
J 0
(-2995 680);
DISPLAY 0.872340 (-2995 680);
PAINT GREEN (-2995 680);
DISPLAY INVISIBLE (-2995 680);
FORCEADD OFFPAGE..2
(-2950 575);
FORCEPROP 2 LAST $XR0 21 
J 0
(-2761 575);
DISPLAY 0.638298 (-2761 575);
PAINT MONO (-2761 575);
FORCEPROP 2 LAST CDS_LIB mstr_standard
J 0
(-2950 575);
PAINT ORANGE (-2950 575);
DISPLAY INVISIBLE (-2950 575);
FORCEPROP 2 LAST PATH I310
J 0
(-2775 650);
DISPLAY 1.021277 (-2775 650);
PAINT ORANGE (-2775 650);
DISPLAY INVISIBLE (-2775 650);
FORCEPROP 1 LAST OFFPAGE TRUE
J 0
(-2625 450);
DISPLAY 0.872340 (-2625 450);
PAINT GREEN (-2625 450);
DISPLAY INVISIBLE (-2625 450);
FORCEPROP 1 LAST COMMENT_BODY TRUE
J 0
(-2995 480);
DISPLAY 0.872340 (-2995 480);
PAINT GREEN (-2995 480);
DISPLAY INVISIBLE (-2995 480);
FORCEADD GND..1
(-2175 425);
FORCEPROP 3 LASTPIN (-2175 475) SIG_NAME GND\g
J 0
(-2165 485);
DISPLAY 0.659574 (-2165 485);
PAINT MONO (-2165 485);
DISPLAY INVISIBLE (-2165 485);
FORCEPROP 2 LAST CDS_LIB mstr_symbols
J 0
(-2175 425);
PAINT ORANGE (-2175 425);
DISPLAY INVISIBLE (-2175 425);
FORCEPROP 1 LAST SIZE 1B
J 0
(-2100 375);
DISPLAY 0.872340 (-2100 375);
PAINT AQUA (-2100 375);
DISPLAY INVISIBLE (-2100 375);
FORCEPROP 1 LAST VOLTAGE 0.0V
J 0
(-2220 382);
DISPLAY 0.340426 (-2220 382);
PAINT SKYBLUE (-2220 382);
DISPLAY INVISIBLE (-2220 382);
FORCEPROP 1 LAST PATH I311
J 0
(-2100 425);
DISPLAY 0.872340 (-2100 425);
PAINT AQUA (-2100 425);
DISPLAY INVISIBLE (-2100 425);
FORCEPROP 1 LAST BODY_TYPE PLUMBING
J 0
(-2220 382);
DISPLAY 0.340426 (-2220 382);
PAINT GREEN (-2220 382);
DISPLAY INVISIBLE (-2220 382);
FORCEPROP 1 LAST HDL_POWER GND
J 0
(-2175 575);
DISPLAY 0.872340 (-2175 575);
PAINT GREEN (-2175 575);
DISPLAY INVISIBLE (-2175 575);
FORCEADD RES..1
(-1900 575);
FORCEPROP 1 LASTPIN (-2000 575) $PN 1
J 0
(-1988 587);
DISPLAY 0.617021 (-1988 587);
PAINT ORANGE (-1988 587);
FORCEPROP 1 LAST LOCATION R1C32
J 0
(-2050 625);
DISPLAY 0.617021 (-2050 625);
PAINT AQUA (-2050 625);
FORCEPROP 1 LASTPIN (-1800 575) $PN 2
J 0
(-1838 587);
DISPLAY 0.617021 (-1838 587);
PAINT ORANGE (-1838 587);
FORCEPROP 1 LAST PART_NUMBER G21796-026
J 0
(-1350 625);
DISPLAY 0.617021 (-1350 625);
PAINT BLUE (-1350 625);
FORCEPROP 1 LAST PACK_TYPE 0402
J 0
(-1100 625);
DISPLAY 0.638298 (-1100 625);
PAINT SKYBLUE (-1100 625);
FORCEPROP 1 LAST WATTAGE 1/16W
J 0
(-1650 625);
DISPLAY 0.617021 (-1650 625);
PAINT SKYBLUE (-1650 625);
FORCEPROP 1 LAST MATERIAL CHIP
J 0
(-1500 625);
DISPLAY 0.638298 (-1500 625);
PAINT SKYBLUE (-1500 625);
FORCEPROP 1 LAST TOLERANCE 1%
J 0
(-1750 625);
DISPLAY 0.617021 (-1750 625);
PAINT SKYBLUE (-1750 625);
FORCEPROP 1 LAST VALUE 1.00K
J 0
(-1900 625);
DISPLAY 0.617021 (-1900 625);
PAINT SKYBLUE (-1900 625);
FORCEPROP 0 LAST ROOM CPU1
J 0
(-1950 725);
DISPLAY 1.021277 (-1950 725);
PAINT ORANGE (-1950 725);
DISPLAY INVISIBLE (-1950 725);
FORCEPROP 1 LAST PATH I312
J 0
(-1950 725);
DISPLAY 0.978723 (-1950 725);
PAINT WHITE (-1950 725);
DISPLAY INVISIBLE (-1950 725);
FORCEPROP 2 LAST CDS_LIB mstr_discrete
J 0
(-1900 575);
PAINT ORANGE (-1900 575);
DISPLAY INVISIBLE (-1900 575);
FORCEPROP 2 LAST SEC 1
J 0
(-1950 775);
DISPLAY 0.680851 (-1950 775);
PAINT MONO (-1950 775);
DISPLAY INVISIBLE (-1950 775);
FORCEPROP 2 LAST SEC_TYPE 0402
J 0
(-1950 775);
DISPLAY 1.021277 (-1950 775);
PAINT ORANGE (-1950 775);
DISPLAY INVISIBLE (-1950 775);
FORCEADD RES..1
(-1900 775);
FORCEPROP 1 LAST MATERIAL CHIP
J 0
(-1500 825);
DISPLAY 0.638298 (-1500 825);
PAINT SKYBLUE (-1500 825);
FORCEPROP 1 LAST PACK_TYPE 0402
J 0
(-1100 825);
DISPLAY 0.638298 (-1100 825);
PAINT SKYBLUE (-1100 825);
FORCEPROP 1 LAST PART_NUMBER G21796-026
J 0
(-1350 825);
DISPLAY 0.617021 (-1350 825);
PAINT BLUE (-1350 825);
FORCEPROP 1 LAST WATTAGE 1/16W
J 0
(-1650 825);
DISPLAY 0.617021 (-1650 825);
PAINT SKYBLUE (-1650 825);
FORCEPROP 1 LAST LOCATION R1C33
J 0
(-2050 825);
DISPLAY 0.617021 (-2050 825);
PAINT AQUA (-2050 825);
FORCEPROP 1 LASTPIN (-2000 775) $PN 1
J 0
(-1988 787);
DISPLAY 0.617021 (-1988 787);
PAINT ORANGE (-1988 787);
FORCEPROP 1 LAST VALUE 1.00K
J 0
(-1900 825);
DISPLAY 0.617021 (-1900 825);
PAINT SKYBLUE (-1900 825);
FORCEPROP 1 LASTPIN (-1800 775) $PN 2
J 0
(-1838 787);
DISPLAY 0.617021 (-1838 787);
PAINT ORANGE (-1838 787);
FORCEPROP 1 LAST TOLERANCE 1%
J 0
(-1750 825);
DISPLAY 0.617021 (-1750 825);
PAINT SKYBLUE (-1750 825);
FORCEPROP 0 LAST ROOM CPU1
J 0
(-1950 925);
DISPLAY 1.021277 (-1950 925);
PAINT ORANGE (-1950 925);
DISPLAY INVISIBLE (-1950 925);
FORCEPROP 1 LAST PATH I313
J 0
(-1950 925);
DISPLAY 0.978723 (-1950 925);
PAINT WHITE (-1950 925);
DISPLAY INVISIBLE (-1950 925);
FORCEPROP 2 LAST SEC 1
J 0
(-1950 975);
DISPLAY 0.680851 (-1950 975);
PAINT MONO (-1950 975);
DISPLAY INVISIBLE (-1950 975);
FORCEPROP 2 LAST SEC_TYPE 0402
J 0
(-1950 975);
DISPLAY 1.021277 (-1950 975);
PAINT ORANGE (-1950 975);
DISPLAY INVISIBLE (-1950 975);
FORCEPROP 2 LAST CDS_LIB mstr_discrete
J 0
(-1900 775);
PAINT ORANGE (-1900 775);
DISPLAY INVISIBLE (-1900 775);
FORCEADD OFFPAGE..2
(-850 575);
FORCEPROP 2 LAST $XR0 55 
J 0
(-661 575);
DISPLAY 0.638298 (-661 575);
PAINT MONO (-661 575);
FORCEPROP 2 LAST CDS_LIB mstr_standard
J 0
(-850 575);
PAINT ORANGE (-850 575);
DISPLAY INVISIBLE (-850 575);
FORCEPROP 2 LAST PATH I314
J 0
(-675 650);
DISPLAY 1.021277 (-675 650);
PAINT ORANGE (-675 650);
DISPLAY INVISIBLE (-675 650);
FORCEPROP 1 LAST OFFPAGE TRUE
J 0
(-525 450);
DISPLAY 0.872340 (-525 450);
PAINT GREEN (-525 450);
DISPLAY INVISIBLE (-525 450);
FORCEPROP 1 LAST COMMENT_BODY TRUE
J 0
(-895 480);
DISPLAY 0.872340 (-895 480);
PAINT GREEN (-895 480);
DISPLAY INVISIBLE (-895 480);
FORCEADD OFFPAGE..2
(-850 775);
FORCEPROP 2 LAST $XR0 55 
J 0
(-661 775);
DISPLAY 0.638298 (-661 775);
PAINT MONO (-661 775);
FORCEPROP 2 LAST CDS_LIB mstr_standard
J 0
(-850 775);
PAINT ORANGE (-850 775);
DISPLAY INVISIBLE (-850 775);
FORCEPROP 2 LAST PATH I315
J 0
(-675 850);
DISPLAY 1.021277 (-675 850);
PAINT ORANGE (-675 850);
DISPLAY INVISIBLE (-675 850);
FORCEPROP 1 LAST OFFPAGE TRUE
J 0
(-525 650);
DISPLAY 0.872340 (-525 650);
PAINT GREEN (-525 650);
DISPLAY INVISIBLE (-525 650);
FORCEPROP 1 LAST COMMENT_BODY TRUE
J 0
(-895 680);
DISPLAY 0.872340 (-895 680);
PAINT GREEN (-895 680);
DISPLAY INVISIBLE (-895 680);
FORCEADD OFFPAGE..2
(-850 975);
FORCEPROP 2 LAST $XR0 55 
J 0
(-661 975);
DISPLAY 0.638298 (-661 975);
PAINT MONO (-661 975);
FORCEPROP 2 LAST CDS_LIB mstr_standard
J 0
(-850 975);
PAINT ORANGE (-850 975);
DISPLAY INVISIBLE (-850 975);
FORCEPROP 2 LAST PATH I316
J 0
(-675 1050);
DISPLAY 1.021277 (-675 1050);
PAINT ORANGE (-675 1050);
DISPLAY INVISIBLE (-675 1050);
FORCEPROP 1 LAST OFFPAGE TRUE
J 0
(-525 850);
DISPLAY 0.872340 (-525 850);
PAINT GREEN (-525 850);
DISPLAY INVISIBLE (-525 850);
FORCEPROP 1 LAST COMMENT_BODY TRUE
J 0
(-895 880);
DISPLAY 0.872340 (-895 880);
PAINT GREEN (-895 880);
DISPLAY INVISIBLE (-895 880);
FORCEADD P3V3_STBY..1
(-2175 1100);
FORCEPROP 3 LASTPIN (-2175 1050) SIG_NAME P3V3_STBY\g
J 0
(-2165 1060);
DISPLAY 0.659574 (-2165 1060);
PAINT MONO (-2165 1060);
DISPLAY INVISIBLE (-2165 1060);
FORCEPROP 1 LAST SIZE 1B
J 0
(-2130 1122);
DISPLAY 0.340426 (-2130 1122);
PAINT GREEN (-2130 1122);
DISPLAY INVISIBLE (-2130 1122);
FORCEPROP 2 LAST CDS_LIB mstr_symbols
J 0
(-2175 1100);
PAINT ORANGE (-2175 1100);
DISPLAY INVISIBLE (-2175 1100);
FORCEPROP 1 LAST PATH I318
J 0
(-2130 1102);
DISPLAY 0.340426 (-2130 1102);
PAINT GREEN (-2130 1102);
DISPLAY INVISIBLE (-2130 1102);
FORCEPROP 1 LAST VOLTAGE 3.3V
J 0
(-2220 1057);
DISPLAY 0.340426 (-2220 1057);
PAINT SKYBLUE (-2220 1057);
DISPLAY INVISIBLE (-2220 1057);
FORCEPROP 1 LAST BODY_TYPE PLUMBING
J 0
(-2220 1057);
DISPLAY 0.340426 (-2220 1057);
PAINT GREEN (-2220 1057);
DISPLAY INVISIBLE (-2220 1057);
FORCEPROP 1 LAST HDL_POWER P3V3_STBY
J 0
(-2475 975);
DISPLAY 0.872340 (-2475 975);
PAINT ORANGE (-2475 975);
DISPLAY INVISIBLE (-2475 975);
FORCEADD RES..1
(-1900 975);
FORCEPROP 1 LAST LOCATION R1C34
J 0
(-2050 1025);
DISPLAY 0.617021 (-2050 1025);
PAINT AQUA (-2050 1025);
FORCEPROP 1 LASTPIN (-2000 975) $PN 1
J 0
(-1988 987);
DISPLAY 0.617021 (-1988 987);
PAINT ORANGE (-1988 987);
FORCEPROP 1 LASTPIN (-1800 975) $PN 2
J 0
(-1838 987);
DISPLAY 0.617021 (-1838 987);
PAINT ORANGE (-1838 987);
FORCEPROP 1 LAST VALUE 10.0K
J 0
(-1900 1025);
DISPLAY 0.617021 (-1900 1025);
PAINT SKYBLUE (-1900 1025);
FORCEPROP 1 LAST TOLERANCE 1%
J 0
(-1750 1025);
DISPLAY 0.617021 (-1750 1025);
PAINT SKYBLUE (-1750 1025);
FORCEPROP 1 LAST WATTAGE 1/16W
J 0
(-1650 1025);
DISPLAY 0.617021 (-1650 1025);
PAINT SKYBLUE (-1650 1025);
FORCEPROP 1 LAST PART_NUMBER G21796-016
J 0
(-1350 1025);
DISPLAY 0.617021 (-1350 1025);
PAINT BLUE (-1350 1025);
FORCEPROP 1 LAST PACK_TYPE 0402
J 0
(-1100 1025);
DISPLAY 0.638298 (-1100 1025);
PAINT SKYBLUE (-1100 1025);
FORCEPROP 1 LAST MATERIAL CHIP
J 0
(-1500 1025);
DISPLAY 0.638298 (-1500 1025);
PAINT SKYBLUE (-1500 1025);
FORCEPROP 2 LAST CDS_LIB mstr_discrete
J 0
(-1900 975);
PAINT ORANGE (-1900 975);
DISPLAY INVISIBLE (-1900 975);
FORCEPROP 2 LAST SEC_TYPE 0402
J 0
(-1950 1175);
DISPLAY 1.021277 (-1950 1175);
PAINT ORANGE (-1950 1175);
DISPLAY INVISIBLE (-1950 1175);
FORCEPROP 2 LAST SEC 1
J 0
(-1950 1175);
DISPLAY 0.680851 (-1950 1175);
PAINT MONO (-1950 1175);
DISPLAY INVISIBLE (-1950 1175);
FORCEPROP 1 LAST PATH I320
J 0
(-1950 1125);
DISPLAY 0.978723 (-1950 1125);
PAINT WHITE (-1950 1125);
DISPLAY INVISIBLE (-1950 1125);
FORCEPROP 0 LAST ROOM CPU1
J 0
(-1950 1125);
DISPLAY 1.021277 (-1950 1125);
PAINT ORANGE (-1950 1125);
DISPLAY INVISIBLE (-1950 1125);
FORCEADD RES..1
(-6425 850);
FORCEPROP 1 LAST PACK_TYPE 0402
J 0
(-6250 900);
DISPLAY 0.617021 (-6250 900);
PAINT SKYBLUE (-6250 900);
FORCEPROP 1 LAST MATERIAL CHIP
J 0
(-6650 900);
DISPLAY 0.638298 (-6650 900);
PAINT SKYBLUE (-6650 900);
FORCEPROP 1 LAST WATTAGE 1/16W
J 0
(-6300 950);
DISPLAY 0.638298 (-6300 950);
PAINT SKYBLUE (-6300 950);
FORCEPROP 1 LAST TOLERANCE 5%
J 0
(-6400 950);
DISPLAY 0.638298 (-6400 950);
PAINT SKYBLUE (-6400 950);
FORCEPROP 1 LAST PART_NUMBER G21497-005
J 0
(-6500 900);
DISPLAY 0.617021 (-6500 900);
PAINT BLUE (-6500 900);
FORCEPROP 1 LASTPIN (-6325 850) $PN 2
J 0
(-6363 862);
DISPLAY 0.617021 (-6363 862);
PAINT ORANGE (-6363 862);
FORCEPROP 1 LAST VALUE 0.0
J 0
(-6500 950);
DISPLAY 0.617021 (-6500 950);
PAINT SKYBLUE (-6500 950);
FORCEPROP 1 LAST LOCATION R9M21
J 0
(-6650 950);
DISPLAY 0.617021 (-6650 950);
PAINT AQUA (-6650 950);
FORCEPROP 1 LASTPIN (-6525 850) $PN 1
J 0
(-6513 862);
DISPLAY 0.617021 (-6513 862);
PAINT ORANGE (-6513 862);
FORCEPROP 2 LAST CDS_LIB mstr_discrete
J 0
(-6425 850);
PAINT ORANGE (-6425 850);
DISPLAY INVISIBLE (-6425 850);
FORCEPROP 0 LAST ROOM CPU1
J 0
(-6325 975);
DISPLAY 1.021277 (-6325 975);
PAINT ORANGE (-6325 975);
DISPLAY INVISIBLE (-6325 975);
FORCEPROP 1 LAST PATH I321
J 0
(-6475 1000);
DISPLAY 0.978723 (-6475 1000);
PAINT WHITE (-6475 1000);
DISPLAY INVISIBLE (-6475 1000);
FORCEPROP 2 LAST SEC_TYPE 0402
J 0
(-6475 1050);
DISPLAY 1.021277 (-6475 1050);
PAINT ORANGE (-6475 1050);
DISPLAY INVISIBLE (-6475 1050);
FORCEPROP 2 LAST SEC 1
J 0
(-6475 1050);
DISPLAY 0.680851 (-6475 1050);
PAINT MONO (-6475 1050);
DISPLAY INVISIBLE (-6475 1050);
FORCEADD RES..1
(-6425 700);
FORCEPROP 1 LAST WATTAGE 1/16W
J 0
(-6300 800);
DISPLAY 0.638298 (-6300 800);
PAINT SKYBLUE (-6300 800);
FORCEPROP 1 LAST PART_NUMBER G21497-005
J 0
(-6500 750);
DISPLAY 0.617021 (-6500 750);
PAINT BLUE (-6500 750);
FORCEPROP 1 LASTPIN (-6325 700) $PN 2
J 0
(-6363 712);
DISPLAY 0.617021 (-6363 712);
PAINT ORANGE (-6363 712);
FORCEPROP 1 LAST PACK_TYPE 0402
J 0
(-6250 750);
DISPLAY 0.617021 (-6250 750);
PAINT SKYBLUE (-6250 750);
FORCEPROP 1 LAST VALUE 0.0
J 2
(-6450 800);
DISPLAY 0.617021 (-6450 800);
PAINT SKYBLUE (-6450 800);
FORCEPROP 1 LAST MATERIAL CHIP
J 0
(-6650 750);
DISPLAY 0.638298 (-6650 750);
PAINT SKYBLUE (-6650 750);
FORCEPROP 1 LAST TOLERANCE 5%
J 0
(-6400 800);
DISPLAY 0.638298 (-6400 800);
PAINT SKYBLUE (-6400 800);
FORCEPROP 1 LAST LOCATION R4A8
J 0
(-6650 800);
DISPLAY 0.617021 (-6650 800);
PAINT AQUA (-6650 800);
FORCEPROP 1 LASTPIN (-6525 700) $PN 1
J 0
(-6513 712);
DISPLAY 0.617021 (-6513 712);
PAINT ORANGE (-6513 712);
FORCEPROP 2 LAST CDS_LIB mstr_discrete
J 0
(-6425 700);
PAINT ORANGE (-6425 700);
DISPLAY INVISIBLE (-6425 700);
FORCEPROP 1 LAST PATH I322
J 0
(-6475 850);
DISPLAY 0.978723 (-6475 850);
PAINT WHITE (-6475 850);
DISPLAY INVISIBLE (-6475 850);
FORCEPROP 2 LAST SEC_TYPE 0402
J 0
(-6475 900);
DISPLAY 1.021277 (-6475 900);
PAINT ORANGE (-6475 900);
DISPLAY INVISIBLE (-6475 900);
FORCEPROP 2 LAST SEC 1
J 0
(-6475 900);
DISPLAY 0.680851 (-6475 900);
PAINT MONO (-6475 900);
DISPLAY INVISIBLE (-6475 900);
FORCEPROP 0 LAST ROOM CPU0
J 0
(-6325 825);
DISPLAY 1.021277 (-6325 825);
PAINT ORANGE (-6325 825);
DISPLAY INVISIBLE (-6325 825);
FORCEADD RES..1
(-6425 550);
FORCEPROP 1 LAST PACK_TYPE 0402
J 0
(-6250 600);
DISPLAY 0.617021 (-6250 600);
PAINT SKYBLUE (-6250 600);
FORCEPROP 1 LAST PART_NUMBER G21497-005
J 0
(-6500 600);
DISPLAY 0.617021 (-6500 600);
PAINT BLUE (-6500 600);
FORCEPROP 1 LASTPIN (-6325 550) $PN 2
J 0
(-6363 562);
DISPLAY 0.617021 (-6363 562);
PAINT ORANGE (-6363 562);
FORCEPROP 1 LAST WATTAGE 1/16W
J 0
(-6300 650);
DISPLAY 0.638298 (-6300 650);
PAINT SKYBLUE (-6300 650);
FORCEPROP 1 LAST MATERIAL CHIP
J 0
(-6650 600);
DISPLAY 0.638298 (-6650 600);
PAINT SKYBLUE (-6650 600);
FORCEPROP 1 LAST TOLERANCE 5%
J 0
(-6400 650);
DISPLAY 0.638298 (-6400 650);
PAINT SKYBLUE (-6400 650);
FORCEPROP 1 LAST VALUE 0.0
J 0
(-6500 650);
DISPLAY 0.617021 (-6500 650);
PAINT SKYBLUE (-6500 650);
FORCEPROP 1 LAST LOCATION R9M20
J 0
(-6650 650);
DISPLAY 0.617021 (-6650 650);
PAINT AQUA (-6650 650);
FORCEPROP 1 LASTPIN (-6525 550) $PN 1
J 0
(-6513 562);
DISPLAY 0.617021 (-6513 562);
PAINT ORANGE (-6513 562);
FORCEPROP 2 LAST CDS_LIB mstr_discrete
J 0
(-6425 550);
PAINT ORANGE (-6425 550);
DISPLAY INVISIBLE (-6425 550);
FORCEPROP 1 LAST PATH I323
J 0
(-6475 700);
DISPLAY 0.978723 (-6475 700);
PAINT WHITE (-6475 700);
DISPLAY INVISIBLE (-6475 700);
FORCEPROP 2 LAST SEC_TYPE 0402
J 0
(-6475 750);
DISPLAY 1.021277 (-6475 750);
PAINT ORANGE (-6475 750);
DISPLAY INVISIBLE (-6475 750);
FORCEPROP 2 LAST SEC 1
J 0
(-6475 750);
DISPLAY 0.680851 (-6475 750);
PAINT MONO (-6475 750);
DISPLAY INVISIBLE (-6475 750);
FORCEPROP 0 LAST ROOM CPU1
J 0
(-6325 675);
DISPLAY 1.021277 (-6325 675);
PAINT ORANGE (-6325 675);
DISPLAY INVISIBLE (-6325 675);
FORCEADD RES..1
(-6425 400);
FORCEPROP 1 LAST WATTAGE 1/16W
J 0
(-6300 500);
DISPLAY 0.638298 (-6300 500);
PAINT SKYBLUE (-6300 500);
FORCEPROP 1 LAST PACK_TYPE 0402
J 0
(-6250 450);
DISPLAY 0.617021 (-6250 450);
PAINT SKYBLUE (-6250 450);
FORCEPROP 1 LAST MATERIAL CHIP
J 0
(-6650 450);
DISPLAY 0.638298 (-6650 450);
PAINT SKYBLUE (-6650 450);
FORCEPROP 1 LASTPIN (-6325 400) $PN 2
J 0
(-6363 412);
DISPLAY 0.617021 (-6363 412);
PAINT ORANGE (-6363 412);
FORCEPROP 1 LAST PART_NUMBER G21497-005
J 0
(-6500 450);
DISPLAY 0.617021 (-6500 450);
PAINT BLUE (-6500 450);
FORCEPROP 1 LAST VALUE 0.0
J 0
(-6500 500);
DISPLAY 0.617021 (-6500 500);
PAINT SKYBLUE (-6500 500);
FORCEPROP 1 LAST TOLERANCE 5%
J 0
(-6400 500);
DISPLAY 0.638298 (-6400 500);
PAINT SKYBLUE (-6400 500);
FORCEPROP 1 LAST LOCATION R4A9
J 0
(-6650 500);
DISPLAY 0.617021 (-6650 500);
PAINT AQUA (-6650 500);
FORCEPROP 1 LASTPIN (-6525 400) $PN 1
J 0
(-6513 412);
DISPLAY 0.617021 (-6513 412);
PAINT ORANGE (-6513 412);
FORCEPROP 2 LAST CDS_LIB mstr_discrete
J 0
(-6425 400);
PAINT ORANGE (-6425 400);
DISPLAY INVISIBLE (-6425 400);
FORCEPROP 2 LAST SEC 1
J 0
(-6475 600);
DISPLAY 0.680851 (-6475 600);
PAINT MONO (-6475 600);
DISPLAY INVISIBLE (-6475 600);
FORCEPROP 1 LAST PATH I324
J 0
(-6475 550);
DISPLAY 0.978723 (-6475 550);
PAINT WHITE (-6475 550);
DISPLAY INVISIBLE (-6475 550);
FORCEPROP 2 LAST SEC_TYPE 0402
J 0
(-6475 600);
DISPLAY 1.021277 (-6475 600);
PAINT ORANGE (-6475 600);
DISPLAY INVISIBLE (-6475 600);
FORCEPROP 0 LAST ROOM CPU0
J 0
(-6325 525);
DISPLAY 1.021277 (-6325 525);
PAINT ORANGE (-6325 525);
DISPLAY INVISIBLE (-6325 525);
FORCEADD OFFPAGE..6
(-7350 700);
FORCEPROP 2 LAST $XR2 182 
J 0
(-7900 700);
DISPLAY 0.638298 (-7900 700);
PAINT MONO (-7900 700);
FORCEPROP 2 LAST $XR1 160 
J 0
(-7780 700);
DISPLAY 0.638298 (-7780 700);
PAINT MONO (-7780 700);
FORCEPROP 2 LAST $XR0 138 
J 0
(-7660 700);
DISPLAY 0.638298 (-7660 700);
PAINT MONO (-7660 700);
FORCEPROP 2 LAST PATH I325
J 0
(-7300 775);
DISPLAY 1.021277 (-7300 775);
PAINT ORANGE (-7300 775);
DISPLAY INVISIBLE (-7300 775);
FORCEPROP 2 LAST CDS_LIB mstr_standard
J 0
(-7350 700);
PAINT ORANGE (-7350 700);
DISPLAY INVISIBLE (-7350 700);
FORCEPROP 1 LAST OFFPAGE TRUE
J 0
(-7025 575);
DISPLAY 0.872340 (-7025 575);
PAINT GREEN (-7025 575);
DISPLAY INVISIBLE (-7025 575);
FORCEPROP 1 LAST COMMENT_BODY TRUE
J 0
(-7250 625);
DISPLAY 0.872340 (-7250 625);
PAINT GREEN (-7250 625);
DISPLAY INVISIBLE (-7250 625);
FORCEADD OFFPAGE..1
(-7350 400);
FORCEPROP 2 LAST $XR2 182 
J 0
(-7842 400);
DISPLAY 0.638298 (-7842 400);
PAINT MONO (-7842 400);
FORCEPROP 2 LAST $XR1 160 
J 0
(-7722 400);
DISPLAY 0.638298 (-7722 400);
PAINT MONO (-7722 400);
FORCEPROP 2 LAST $XR0 138 
J 0
(-7602 400);
DISPLAY 0.638298 (-7602 400);
PAINT MONO (-7602 400);
FORCEPROP 2 LAST CDS_LIB mstr_standard
J 0
(-7350 400);
PAINT ORANGE (-7350 400);
DISPLAY INVISIBLE (-7350 400);
FORCEPROP 2 LAST PATH I326
J 0
(-7300 475);
DISPLAY 1.021277 (-7300 475);
PAINT ORANGE (-7300 475);
DISPLAY INVISIBLE (-7300 475);
FORCEPROP 1 LAST OFFPAGE TRUE
J 0
(-7025 275);
DISPLAY 0.872340 (-7025 275);
PAINT GREEN (-7025 275);
DISPLAY INVISIBLE (-7025 275);
FORCEPROP 1 LAST COMMENT_BODY TRUE
J 0
(-7225 300);
DISPLAY 0.872340 (-7225 300);
PAINT GREEN (-7225 300);
DISPLAY INVISIBLE (-7225 300);
FORCEADD OFFPAGE..3
(-5350 850);
FORCEPROP 2 LAST $XR0 55 
J 0
(-5136 850);
DISPLAY 0.638298 (-5136 850);
PAINT MONO (-5136 850);
FORCEPROP 2 LAST PATH I327
J 0
(-5300 925);
DISPLAY 1.021277 (-5300 925);
PAINT ORANGE (-5300 925);
DISPLAY INVISIBLE (-5300 925);
FORCEPROP 2 LAST CDS_LIB mstr_standard
J 0
(-5350 850);
PAINT ORANGE (-5350 850);
DISPLAY INVISIBLE (-5350 850);
FORCEPROP 1 LAST OFFPAGE TRUE
J 0
(-5025 725);
DISPLAY 0.872340 (-5025 725);
PAINT GREEN (-5025 725);
DISPLAY INVISIBLE (-5025 725);
FORCEPROP 1 LAST COMMENT_BODY TRUE
J 0
(-5400 750);
DISPLAY 0.872340 (-5400 750);
PAINT GREEN (-5400 750);
DISPLAY INVISIBLE (-5400 750);
FORCEADD OFFPAGE..3
(-5350 700);
FORCEPROP 2 LAST $XR0 21 
J 0
(-5136 700);
DISPLAY 0.638298 (-5136 700);
PAINT MONO (-5136 700);
FORCEPROP 2 LAST CDS_LIB mstr_standard
J 0
(-5350 700);
PAINT ORANGE (-5350 700);
DISPLAY INVISIBLE (-5350 700);
FORCEPROP 2 LAST PATH I328
J 0
(-5175 775);
DISPLAY 1.021277 (-5175 775);
PAINT ORANGE (-5175 775);
DISPLAY INVISIBLE (-5175 775);
FORCEPROP 1 LAST OFFPAGE TRUE
J 0
(-5025 575);
DISPLAY 0.872340 (-5025 575);
PAINT GREEN (-5025 575);
DISPLAY INVISIBLE (-5025 575);
FORCEPROP 1 LAST COMMENT_BODY TRUE
J 0
(-5400 600);
DISPLAY 0.872340 (-5400 600);
PAINT GREEN (-5400 600);
DISPLAY INVISIBLE (-5400 600);
FORCEADD OFFPAGE..2
(-5350 550);
FORCEPROP 2 LAST $XR0 55 
J 0
(-5161 550);
DISPLAY 0.638298 (-5161 550);
PAINT MONO (-5161 550);
FORCEPROP 2 LAST CDS_LIB mstr_standard
J 0
(-5350 550);
PAINT ORANGE (-5350 550);
DISPLAY INVISIBLE (-5350 550);
FORCEPROP 2 LAST PATH I329
J 0
(-5175 625);
DISPLAY 1.021277 (-5175 625);
PAINT ORANGE (-5175 625);
DISPLAY INVISIBLE (-5175 625);
FORCEPROP 1 LAST OFFPAGE TRUE
J 0
(-5025 425);
DISPLAY 0.872340 (-5025 425);
PAINT GREEN (-5025 425);
DISPLAY INVISIBLE (-5025 425);
FORCEPROP 1 LAST COMMENT_BODY TRUE
J 0
(-5395 455);
DISPLAY 0.872340 (-5395 455);
PAINT GREEN (-5395 455);
DISPLAY INVISIBLE (-5395 455);
FORCEADD OFFPAGE..2
(-5350 400);
FORCEPROP 2 LAST $XR0 21 
J 0
(-5161 400);
DISPLAY 0.638298 (-5161 400);
PAINT MONO (-5161 400);
FORCEPROP 2 LAST CDS_LIB mstr_standard
J 0
(-5350 400);
PAINT ORANGE (-5350 400);
DISPLAY INVISIBLE (-5350 400);
FORCEPROP 2 LAST PATH I330
J 0
(-5175 475);
DISPLAY 1.021277 (-5175 475);
PAINT ORANGE (-5175 475);
DISPLAY INVISIBLE (-5175 475);
FORCEPROP 1 LAST OFFPAGE TRUE
J 0
(-5025 275);
DISPLAY 0.872340 (-5025 275);
PAINT GREEN (-5025 275);
DISPLAY INVISIBLE (-5025 275);
FORCEPROP 1 LAST COMMENT_BODY TRUE
J 0
(-5395 305);
DISPLAY 0.872340 (-5395 305);
PAINT GREEN (-5395 305);
DISPLAY INVISIBLE (-5395 305);
FORCEADD RES..2
(-7650 1700);
FORCEPROP 1 LAST PACK_TYPE 0402
J 0
(-7610 1525);
DISPLAY 0.617021 (-7610 1525);
PAINT SKYBLUE (-7610 1525);
FORCEPROP 1 LAST PART_NUMBER G21796-027
J 0
(-7610 1575);
DISPLAY 0.617021 (-7610 1575);
PAINT BLUE (-7610 1575);
FORCEPROP 1 LAST MATERIAL EMPTY
J 0
(-7560 1625);
DISPLAY 0.617021 (-7560 1625);
PAINT RED (-7560 1625);
FORCEPROP 1 LAST WATTAGE 1/16W
J 0
(-7535 1675);
DISPLAY 0.617021 (-7535 1675);
PAINT SKYBLUE (-7535 1675);
FORCEPROP 1 LAST TOLERANCE 1%
J 0
(-7505 1725);
DISPLAY 0.617021 (-7505 1725);
PAINT SKYBLUE (-7505 1725);
FORCEPROP 1 LASTPIN (-7650 1600) $PN 2
J 0
(-7645 1610);
DISPLAY 0.617021 (-7645 1610);
PAINT ORANGE (-7645 1610);
FORCEPROP 1 LASTPIN (-7650 1800) $PN 1
J 0
(-7645 1762);
DISPLAY 0.617021 (-7645 1762);
PAINT ORANGE (-7645 1762);
FORCEPROP 1 LAST LOCATION R3P54
J 0
(-7605 1825);
DISPLAY 0.617021 (-7605 1825);
PAINT AQUA (-7605 1825);
FORCEPROP 1 LAST VALUE 3.32K
J 0
(-7555 1775);
DISPLAY 0.617021 (-7555 1775);
PAINT SKYBLUE (-7555 1775);
FORCEPROP 2 LAST CDS_LIB mstr_discrete
J 0
(-7650 1700);
PAINT ORANGE (-7650 1700);
DISPLAY INVISIBLE (-7650 1700);
FORCEPROP 0 LAST ROOM CPU0
J 0
(-7600 1925);
DISPLAY 1.021277 (-7600 1925);
PAINT ORANGE (-7600 1925);
DISPLAY INVISIBLE (-7600 1925);
FORCEPROP 1 LAST PATH I331
J 0
(-7600 1875);
DISPLAY 0.978723 (-7600 1875);
PAINT WHITE (-7600 1875);
DISPLAY INVISIBLE (-7600 1875);
FORCEPROP 2 LAST SEC 1
J 0
(-7600 1925);
DISPLAY 0.680851 (-7600 1925);
PAINT MONO (-7600 1925);
DISPLAY INVISIBLE (-7600 1925);
FORCEPROP 2 LAST SEC_TYPE 0402
J 0
(-7600 1925);
DISPLAY 1.021277 (-7600 1925);
PAINT ORANGE (-7600 1925);
DISPLAY INVISIBLE (-7600 1925);
FORCEADD P3V3_STBY..1
(-7650 1950);
FORCEPROP 3 LASTPIN (-7650 1900) SIG_NAME P3V3_STBY\g
J 0
(-7640 1910);
DISPLAY 0.659574 (-7640 1910);
PAINT MONO (-7640 1910);
DISPLAY INVISIBLE (-7640 1910);
FORCEPROP 1 LAST VOLTAGE 3.3V
J 0
(-7695 1907);
DISPLAY 0.340426 (-7695 1907);
PAINT SKYBLUE (-7695 1907);
DISPLAY INVISIBLE (-7695 1907);
FORCEPROP 1 LAST PATH I332
J 0
(-7605 1952);
DISPLAY 0.340426 (-7605 1952);
PAINT GREEN (-7605 1952);
DISPLAY INVISIBLE (-7605 1952);
FORCEPROP 2 LAST CDS_LIB mstr_symbols
J 0
(-7650 1950);
PAINT ORANGE (-7650 1950);
DISPLAY INVISIBLE (-7650 1950);
FORCEPROP 1 LAST SIZE 1B
J 0
(-7605 1972);
DISPLAY 0.340426 (-7605 1972);
PAINT GREEN (-7605 1972);
DISPLAY INVISIBLE (-7605 1972);
FORCEPROP 1 LAST BODY_TYPE PLUMBING
J 0
(-7695 1907);
DISPLAY 0.340426 (-7695 1907);
PAINT GREEN (-7695 1907);
DISPLAY INVISIBLE (-7695 1907);
FORCEPROP 1 LAST HDL_POWER P3V3_STBY
J 0
(-7950 1825);
DISPLAY 0.872340 (-7950 1825);
PAINT ORANGE (-7950 1825);
DISPLAY INVISIBLE (-7950 1825);
FORCEADD RES..2
(-7650 1325);
FORCEPROP 1 LAST PART_NUMBER G21796-026
J 0
(-7610 1200);
DISPLAY 0.617021 (-7610 1200);
PAINT BLUE (-7610 1200);
FORCEPROP 1 LAST MATERIAL CHIP
J 0
(-7610 1250);
DISPLAY 0.617021 (-7610 1250);
PAINT SKYBLUE (-7610 1250);
FORCEPROP 1 LAST WATTAGE 1/16W
J 0
(-7610 1300);
DISPLAY 0.617021 (-7610 1300);
PAINT SKYBLUE (-7610 1300);
FORCEPROP 1 LAST VALUE 1.00K
J 0
(-7605 1400);
DISPLAY 0.617021 (-7605 1400);
PAINT SKYBLUE (-7605 1400);
FORCEPROP 1 LAST LOCATION R3P56
J 0
(-7605 1450);
DISPLAY 0.617021 (-7605 1450);
PAINT AQUA (-7605 1450);
FORCEPROP 1 LASTPIN (-7650 1225) $PN 2
J 0
(-7645 1235);
DISPLAY 0.617021 (-7645 1235);
PAINT ORANGE (-7645 1235);
FORCEPROP 1 LAST PACK_TYPE 0402
J 0
(-7610 1150);
DISPLAY 0.617021 (-7610 1150);
PAINT SKYBLUE (-7610 1150);
FORCEPROP 1 LASTPIN (-7650 1425) $PN 1
J 0
(-7645 1387);
DISPLAY 0.617021 (-7645 1387);
PAINT ORANGE (-7645 1387);
FORCEPROP 1 LAST TOLERANCE 1%
J 0
(-7605 1350);
DISPLAY 0.617021 (-7605 1350);
PAINT SKYBLUE (-7605 1350);
FORCEPROP 2 LAST CDS_LIB mstr_discrete
J 0
(-7650 1325);
PAINT ORANGE (-7650 1325);
DISPLAY INVISIBLE (-7650 1325);
FORCEPROP 1 LAST PATH I333
J 0
(-7600 1500);
DISPLAY 0.978723 (-7600 1500);
PAINT WHITE (-7600 1500);
DISPLAY INVISIBLE (-7600 1500);
FORCEPROP 0 LAST ROOM CPU0
J 0
(-7600 1550);
DISPLAY 1.021277 (-7600 1550);
PAINT ORANGE (-7600 1550);
DISPLAY INVISIBLE (-7600 1550);
FORCEPROP 2 LAST SEC 1
J 0
(-7600 1550);
DISPLAY 0.680851 (-7600 1550);
PAINT MONO (-7600 1550);
DISPLAY INVISIBLE (-7600 1550);
FORCEPROP 2 LAST SEC_TYPE 0402
J 0
(-7600 1550);
DISPLAY 1.021277 (-7600 1550);
PAINT ORANGE (-7600 1550);
DISPLAY INVISIBLE (-7600 1550);
FORCEADD GND..1
(-7650 1075);
FORCEPROP 3 LASTPIN (-7650 1125) SIG_NAME GND\g
J 0
(-7640 1135);
DISPLAY 0.659574 (-7640 1135);
PAINT MONO (-7640 1135);
DISPLAY INVISIBLE (-7640 1135);
FORCEPROP 1 LAST VOLTAGE 0.0V
J 0
(-7695 1032);
DISPLAY 0.340426 (-7695 1032);
PAINT SKYBLUE (-7695 1032);
DISPLAY INVISIBLE (-7695 1032);
FORCEPROP 2 LAST CDS_LIB mstr_symbols
J 0
(-7650 1075);
PAINT ORANGE (-7650 1075);
DISPLAY INVISIBLE (-7650 1075);
FORCEPROP 1 LAST SIZE 1B
J 0
(-7575 1025);
DISPLAY 0.872340 (-7575 1025);
PAINT AQUA (-7575 1025);
DISPLAY INVISIBLE (-7575 1025);
FORCEPROP 1 LAST PATH I334
J 0
(-7575 1075);
DISPLAY 0.872340 (-7575 1075);
PAINT AQUA (-7575 1075);
DISPLAY INVISIBLE (-7575 1075);
FORCEPROP 1 LAST BODY_TYPE PLUMBING
J 0
(-7695 1032);
DISPLAY 0.340426 (-7695 1032);
PAINT GREEN (-7695 1032);
DISPLAY INVISIBLE (-7695 1032);
FORCEPROP 1 LAST HDL_POWER GND
J 0
(-7650 1225);
DISPLAY 0.872340 (-7650 1225);
PAINT GREEN (-7650 1225);
DISPLAY INVISIBLE (-7650 1225);
FORCEADD OFFPAGE..2
(-4925 1550);
FORCEPROP 2 LAST $XR0 55 
J 0
(-4736 1550);
DISPLAY 0.638298 (-4736 1550);
PAINT MONO (-4736 1550);
FORCEPROP 2 LAST PATH I335
J 0
(-4750 1625);
DISPLAY 1.021277 (-4750 1625);
PAINT ORANGE (-4750 1625);
DISPLAY INVISIBLE (-4750 1625);
FORCEPROP 2 LAST CDS_LIB mstr_standard
J 0
(-4925 1550);
PAINT ORANGE (-4925 1550);
DISPLAY INVISIBLE (-4925 1550);
FORCEPROP 1 LAST OFFPAGE TRUE
J 0
(-4600 1425);
DISPLAY 0.872340 (-4600 1425);
PAINT GREEN (-4600 1425);
DISPLAY INVISIBLE (-4600 1425);
FORCEPROP 1 LAST COMMENT_BODY TRUE
J 0
(-4970 1455);
DISPLAY 0.872340 (-4970 1455);
PAINT GREEN (-4970 1455);
DISPLAY INVISIBLE (-4970 1455);
FORCEADD RES..2
(-6025 1725);
FORCEPROP 1 LAST PART_NUMBER G21796-027
J 0
(-5985 1600);
DISPLAY 0.617021 (-5985 1600);
PAINT BLUE (-5985 1600);
FORCEPROP 1 LAST MATERIAL EMPTY
J 0
(-5910 1650);
DISPLAY 0.617021 (-5910 1650);
PAINT RED (-5910 1650);
FORCEPROP 1 LAST WATTAGE 1/16W
J 0
(-5885 1700);
DISPLAY 0.617021 (-5885 1700);
PAINT SKYBLUE (-5885 1700);
FORCEPROP 1 LAST VALUE 3.32K
J 0
(-5930 1800);
DISPLAY 0.617021 (-5930 1800);
PAINT SKYBLUE (-5930 1800);
FORCEPROP 1 LAST TOLERANCE 1%
J 0
(-5855 1750);
DISPLAY 0.617021 (-5855 1750);
PAINT SKYBLUE (-5855 1750);
FORCEPROP 1 LASTPIN (-6025 1625) $PN 2
J 0
(-6020 1635);
DISPLAY 0.617021 (-6020 1635);
PAINT ORANGE (-6020 1635);
FORCEPROP 1 LASTPIN (-6025 1825) $PN 1
J 0
(-6020 1787);
DISPLAY 0.617021 (-6020 1787);
PAINT ORANGE (-6020 1787);
FORCEPROP 1 LAST PACK_TYPE 0402
J 0
(-5985 1550);
DISPLAY 0.617021 (-5985 1550);
PAINT SKYBLUE (-5985 1550);
FORCEPROP 1 LAST LOCATION R1C35
J 0
(-5980 1850);
DISPLAY 0.617021 (-5980 1850);
PAINT AQUA (-5980 1850);
FORCEPROP 2 LAST CDS_LIB mstr_discrete
J 0
(-6025 1725);
PAINT ORANGE (-6025 1725);
DISPLAY INVISIBLE (-6025 1725);
FORCEPROP 2 LAST SEC_TYPE 0402
J 0
(-5975 1950);
DISPLAY 1.021277 (-5975 1950);
PAINT ORANGE (-5975 1950);
DISPLAY INVISIBLE (-5975 1950);
FORCEPROP 2 LAST SEC 1
J 0
(-5975 1950);
DISPLAY 0.680851 (-5975 1950);
PAINT MONO (-5975 1950);
DISPLAY INVISIBLE (-5975 1950);
FORCEPROP 1 LAST PATH I336
J 0
(-5975 1900);
DISPLAY 0.978723 (-5975 1900);
PAINT WHITE (-5975 1900);
DISPLAY INVISIBLE (-5975 1900);
FORCEPROP 0 LAST ROOM CPU1
J 0
(-5975 1950);
DISPLAY 1.021277 (-5975 1950);
PAINT ORANGE (-5975 1950);
DISPLAY INVISIBLE (-5975 1950);
FORCEADD RES..2
(-6025 1350);
FORCEPROP 1 LAST PART_NUMBER G21796-026
J 0
(-5985 1225);
DISPLAY 0.617021 (-5985 1225);
PAINT BLUE (-5985 1225);
FORCEPROP 1 LAST PACK_TYPE 0402
J 0
(-5985 1175);
DISPLAY 0.617021 (-5985 1175);
PAINT SKYBLUE (-5985 1175);
FORCEPROP 1 LAST WATTAGE 1/16W
J 0
(-5985 1325);
DISPLAY 0.617021 (-5985 1325);
PAINT SKYBLUE (-5985 1325);
FORCEPROP 1 LAST MATERIAL CHIP
J 0
(-5985 1275);
DISPLAY 0.617021 (-5985 1275);
PAINT SKYBLUE (-5985 1275);
FORCEPROP 1 LASTPIN (-6025 1250) $PN 2
J 0
(-6020 1260);
DISPLAY 0.617021 (-6020 1260);
PAINT ORANGE (-6020 1260);
FORCEPROP 1 LASTPIN (-6025 1450) $PN 1
J 0
(-6020 1412);
DISPLAY 0.617021 (-6020 1412);
PAINT ORANGE (-6020 1412);
FORCEPROP 1 LAST LOCATION R1C36
J 0
(-5980 1475);
DISPLAY 0.617021 (-5980 1475);
PAINT AQUA (-5980 1475);
FORCEPROP 1 LAST VALUE 1.00K
J 0
(-5980 1425);
DISPLAY 0.617021 (-5980 1425);
PAINT SKYBLUE (-5980 1425);
FORCEPROP 1 LAST TOLERANCE 1%
J 0
(-5980 1375);
DISPLAY 0.617021 (-5980 1375);
PAINT SKYBLUE (-5980 1375);
FORCEPROP 2 LAST CDS_LIB mstr_discrete
J 0
(-6025 1350);
PAINT ORANGE (-6025 1350);
DISPLAY INVISIBLE (-6025 1350);
FORCEPROP 1 LAST PATH I337
J 0
(-5975 1525);
DISPLAY 0.978723 (-5975 1525);
PAINT WHITE (-5975 1525);
DISPLAY INVISIBLE (-5975 1525);
FORCEPROP 2 LAST SEC_TYPE 0402
J 0
(-5975 1575);
DISPLAY 1.021277 (-5975 1575);
PAINT ORANGE (-5975 1575);
DISPLAY INVISIBLE (-5975 1575);
FORCEPROP 2 LAST SEC 1
J 0
(-5975 1575);
DISPLAY 0.680851 (-5975 1575);
PAINT MONO (-5975 1575);
DISPLAY INVISIBLE (-5975 1575);
FORCEPROP 0 LAST ROOM CPU1
J 0
(-5975 1575);
DISPLAY 1.021277 (-5975 1575);
PAINT ORANGE (-5975 1575);
DISPLAY INVISIBLE (-5975 1575);
FORCEADD GND..1
(-6025 1100);
FORCEPROP 3 LASTPIN (-6025 1150) SIG_NAME GND\g
J 0
(-6015 1160);
DISPLAY 0.659574 (-6015 1160);
PAINT MONO (-6015 1160);
DISPLAY INVISIBLE (-6015 1160);
FORCEPROP 1 LAST VOLTAGE 0.0V
J 0
(-6070 1057);
DISPLAY 0.340426 (-6070 1057);
PAINT SKYBLUE (-6070 1057);
DISPLAY INVISIBLE (-6070 1057);
FORCEPROP 2 LAST CDS_LIB mstr_symbols
J 0
(-6025 1100);
PAINT ORANGE (-6025 1100);
DISPLAY INVISIBLE (-6025 1100);
FORCEPROP 1 LAST PATH I338
J 0
(-5950 1100);
DISPLAY 0.872340 (-5950 1100);
PAINT AQUA (-5950 1100);
DISPLAY INVISIBLE (-5950 1100);
FORCEPROP 1 LAST SIZE 1B
J 0
(-5950 1050);
DISPLAY 0.872340 (-5950 1050);
PAINT AQUA (-5950 1050);
DISPLAY INVISIBLE (-5950 1050);
FORCEPROP 1 LAST BODY_TYPE PLUMBING
J 0
(-6070 1057);
DISPLAY 0.340426 (-6070 1057);
PAINT GREEN (-6070 1057);
DISPLAY INVISIBLE (-6070 1057);
FORCEPROP 1 LAST HDL_POWER GND
J 0
(-6025 1250);
DISPLAY 0.872340 (-6025 1250);
PAINT GREEN (-6025 1250);
DISPLAY INVISIBLE (-6025 1250);
FORCEADD P3V3_STBY..1
(-6025 1975);
FORCEPROP 3 LASTPIN (-6025 1925) SIG_NAME P3V3_STBY\g
J 0
(-6015 1935);
DISPLAY 0.659574 (-6015 1935);
PAINT MONO (-6015 1935);
DISPLAY INVISIBLE (-6015 1935);
FORCEPROP 2 LAST CDS_LIB mstr_symbols
J 0
(-6025 1975);
PAINT ORANGE (-6025 1975);
DISPLAY INVISIBLE (-6025 1975);
FORCEPROP 1 LAST VOLTAGE 3.3V
J 0
(-6070 1932);
DISPLAY 0.340426 (-6070 1932);
PAINT SKYBLUE (-6070 1932);
DISPLAY INVISIBLE (-6070 1932);
FORCEPROP 1 LAST PATH I339
J 0
(-5980 1977);
DISPLAY 0.340426 (-5980 1977);
PAINT GREEN (-5980 1977);
DISPLAY INVISIBLE (-5980 1977);
FORCEPROP 1 LAST SIZE 1B
J 0
(-5980 1997);
DISPLAY 0.340426 (-5980 1997);
PAINT GREEN (-5980 1997);
DISPLAY INVISIBLE (-5980 1997);
FORCEPROP 1 LAST BODY_TYPE PLUMBING
J 0
(-6070 1932);
DISPLAY 0.340426 (-6070 1932);
PAINT GREEN (-6070 1932);
DISPLAY INVISIBLE (-6070 1932);
FORCEPROP 1 LAST HDL_POWER P3V3_STBY
J 0
(-6325 1850);
DISPLAY 0.872340 (-6325 1850);
PAINT ORANGE (-6325 1850);
DISPLAY INVISIBLE (-6325 1850);
FORCEADD SN74LVC2G07DCKR-GP..1
(-3225 4150);
FORCEPROP 2 LASTPIN (-3550 4200) $PN 1
J 2
(-3560 4210);
DISPLAY 0.808511 (-3560 4210);
PAINT ORANGE (-3560 4210);
FORCEPROP 2 LASTPIN (-2900 4150) $PN 5
J 0
(-2890 4160);
DISPLAY 0.808511 (-2890 4160);
PAINT ORANGE (-2890 4160);
FORCEPROP 2 LASTPIN (-2900 4100) $PN 4
J 0
(-2890 4110);
DISPLAY 0.808511 (-2890 4110);
PAINT ORANGE (-2890 4110);
FORCEPROP 1 LAST LOCATION U8F3
J 0
(-3400 4310);
DISPLAY 0.617021 (-3400 4310);
PAINT GREEN (-3400 4310);
FORCEPROP 2 LASTPIN (-3550 4150) $PN 2
J 2
(-3560 4160);
DISPLAY 0.808511 (-3560 4160);
PAINT ORANGE (-3560 4160);
FORCEPROP 2 LASTPIN (-2900 4200) $PN 6
J 0
(-2890 4210);
DISPLAY 0.808511 (-2890 4210);
PAINT ORANGE (-2890 4210);
FORCEPROP 2 LASTPIN (-3550 4100) $PN 3
J 2
(-3560 4110);
DISPLAY 0.808511 (-3560 4110);
PAINT ORANGE (-3560 4110);
FORCEPROP 1 LAST VALUE SN74LVC2G07DCKR-GP
J 0
(-3400 3970);
DISPLAY 0.617021 (-3400 3970);
PAINT GREEN (-3400 3970);
FORCEPROP 1 LAST PACK_TYPE DISCRET-G4
J 0
(-3225 4150);
DISPLAY 0.617021 (-3225 4150);
PAINT GREEN (-3225 4150);
DISPLAY INVISIBLE (-3225 4150);
FORCEPROP 1 LAST PART_NUMBER 73.02G07.02J
J 0
(-3225 4150);
DISPLAY 0.617021 (-3225 4150);
PAINT GREEN (-3225 4150);
DISPLAY INVISIBLE (-3225 4150);
FORCEPROP 1 LAST PATH I340
J 0
(-3225 4150);
DISPLAY 0.617021 (-3225 4150);
PAINT GREEN (-3225 4150);
DISPLAY INVISIBLE (-3225 4150);
FORCEPROP 2 LAST SEC 1
J 0
(-3400 4350);
DISPLAY 0.680851 (-3400 4350);
PAINT MONO (-3400 4350);
DISPLAY INVISIBLE (-3400 4350);
FORCEPROP 2 LAST SEC_TYPE DISCRET-G4
J 0
(-3400 4350);
DISPLAY 1.021277 (-3400 4350);
PAINT ORANGE (-3400 4350);
DISPLAY INVISIBLE (-3400 4350);
FORCEPROP 2 LAST CDS_LIB w_hdl
J 0
(-3225 4150);
PAINT MONO (-3225 4150);
DISPLAY INVISIBLE (-3225 4150);
FORCEPROP 1 LAST CDS_LMAN_SYM_OUTLINE -175,150,175,-150
J 0
(-3225 4150);
DISPLAY 0.468085 (-3225 4150);
PAINT GREEN (-3225 4150);
DISPLAY INVISIBLE (-3225 4150);
FORCEADD GND..1
(-3650 3950);
FORCEPROP 3 LASTPIN (-3650 4000) SIG_NAME GND\g
J 0
(-3640 4010);
DISPLAY 0.659574 (-3640 4010);
PAINT MONO (-3640 4010);
DISPLAY INVISIBLE (-3640 4010);
FORCEPROP 1 LAST HDL_POWER GND
J 0
(-3650 4100);
DISPLAY 0.872340 (-3650 4100);
PAINT GREEN (-3650 4100);
DISPLAY INVISIBLE (-3650 4100);
FORCEPROP 1 LAST BODY_TYPE PLUMBING
J 0
(-3695 3907);
DISPLAY 0.340426 (-3695 3907);
PAINT GREEN (-3695 3907);
DISPLAY INVISIBLE (-3695 3907);
FORCEPROP 1 LAST SIZE 1B
J 0
(-3575 3900);
DISPLAY 0.872340 (-3575 3900);
PAINT AQUA (-3575 3900);
DISPLAY INVISIBLE (-3575 3900);
FORCEPROP 1 LAST VOLTAGE 0.0V
J 0
(-3695 3907);
DISPLAY 0.340426 (-3695 3907);
PAINT SKYBLUE (-3695 3907);
DISPLAY INVISIBLE (-3695 3907);
FORCEPROP 1 LAST PATH I341
J 0
(-3575 3950);
DISPLAY 0.872340 (-3575 3950);
PAINT AQUA (-3575 3950);
DISPLAY INVISIBLE (-3575 3950);
FORCEPROP 2 LAST CDS_LIB mstr_symbols
J 0
(-3650 3950);
PAINT MONO (-3650 3950);
DISPLAY INVISIBLE (-3650 3950);
FORCEADD SN74LVC2G07DCKR-GP..1
(-3225 2950);
FORCEPROP 1 LAST LOCATION U8G1
J 0
(-3400 3110);
DISPLAY 0.617021 (-3400 3110);
PAINT GREEN (-3400 3110);
FORCEPROP 2 LASTPIN (-2900 2950) $PN 5
J 0
(-2890 2960);
DISPLAY 0.808511 (-2890 2960);
PAINT ORANGE (-2890 2960);
FORCEPROP 2 LASTPIN (-3550 3000) $PN 1
J 2
(-3560 3010);
DISPLAY 0.808511 (-3560 3010);
PAINT ORANGE (-3560 3010);
FORCEPROP 2 LASTPIN (-3550 2950) $PN 2
J 2
(-3560 2960);
DISPLAY 0.808511 (-3560 2960);
PAINT ORANGE (-3560 2960);
FORCEPROP 2 LASTPIN (-3550 2900) $PN 3
J 2
(-3560 2910);
DISPLAY 0.808511 (-3560 2910);
PAINT ORANGE (-3560 2910);
FORCEPROP 2 LASTPIN (-2900 2900) $PN 4
J 0
(-2890 2910);
DISPLAY 0.808511 (-2890 2910);
PAINT ORANGE (-2890 2910);
FORCEPROP 2 LASTPIN (-2900 3000) $PN 6
J 0
(-2890 3010);
DISPLAY 0.808511 (-2890 3010);
PAINT ORANGE (-2890 3010);
FORCEPROP 1 LAST VALUE SN74LVC2G07DCKR-GP
J 0
(-3400 2770);
DISPLAY 0.617021 (-3400 2770);
PAINT GREEN (-3400 2770);
FORCEPROP 1 LAST PART_NUMBER 73.02G07.02J
J 0
(-3225 2950);
DISPLAY 0.617021 (-3225 2950);
PAINT GREEN (-3225 2950);
DISPLAY INVISIBLE (-3225 2950);
FORCEPROP 1 LAST CDS_LMAN_SYM_OUTLINE -175,150,175,-150
J 0
(-3225 2950);
DISPLAY 0.468085 (-3225 2950);
PAINT GREEN (-3225 2950);
DISPLAY INVISIBLE (-3225 2950);
FORCEPROP 1 LAST PATH I342
J 0
(-3225 2950);
DISPLAY 0.617021 (-3225 2950);
PAINT GREEN (-3225 2950);
DISPLAY INVISIBLE (-3225 2950);
FORCEPROP 2 LAST CDS_LIB w_hdl
J 0
(-3225 2950);
PAINT MONO (-3225 2950);
DISPLAY INVISIBLE (-3225 2950);
FORCEPROP 2 LAST SEC_TYPE DISCRET-G4
J 0
(-3400 3150);
DISPLAY 1.021277 (-3400 3150);
PAINT ORANGE (-3400 3150);
DISPLAY INVISIBLE (-3400 3150);
FORCEPROP 2 LAST SEC 1
J 0
(-3400 3150);
DISPLAY 0.680851 (-3400 3150);
PAINT MONO (-3400 3150);
DISPLAY INVISIBLE (-3400 3150);
FORCEPROP 1 LAST PACK_TYPE DISCRET-G4
J 0
(-3225 2950);
DISPLAY 0.617021 (-3225 2950);
PAINT GREEN (-3225 2950);
DISPLAY INVISIBLE (-3225 2950);
FORCEADD GND..1
(-3650 2750);
FORCEPROP 3 LASTPIN (-3650 2800) SIG_NAME GND\g
J 0
(-3640 2810);
DISPLAY 0.659574 (-3640 2810);
PAINT MONO (-3640 2810);
DISPLAY INVISIBLE (-3640 2810);
FORCEPROP 2 LAST CDS_LIB mstr_symbols
J 0
(-3650 2750);
PAINT MONO (-3650 2750);
DISPLAY INVISIBLE (-3650 2750);
FORCEPROP 1 LAST PATH I343
J 0
(-3575 2750);
DISPLAY 0.872340 (-3575 2750);
PAINT AQUA (-3575 2750);
DISPLAY INVISIBLE (-3575 2750);
FORCEPROP 1 LAST VOLTAGE 0.0V
J 0
(-3695 2707);
DISPLAY 0.340426 (-3695 2707);
PAINT SKYBLUE (-3695 2707);
DISPLAY INVISIBLE (-3695 2707);
FORCEPROP 1 LAST SIZE 1B
J 0
(-3575 2700);
DISPLAY 0.872340 (-3575 2700);
PAINT AQUA (-3575 2700);
DISPLAY INVISIBLE (-3575 2700);
FORCEPROP 1 LAST BODY_TYPE PLUMBING
J 0
(-3695 2707);
DISPLAY 0.340426 (-3695 2707);
PAINT GREEN (-3695 2707);
DISPLAY INVISIBLE (-3695 2707);
FORCEPROP 1 LAST HDL_POWER GND
J 0
(-3650 2900);
DISPLAY 0.872340 (-3650 2900);
PAINT GREEN (-3650 2900);
DISPLAY INVISIBLE (-3650 2900);
FORCEADD CAD_NOTE..1
(-1400 3725);
FORCEPROP 0 LAST L2 NEXT TO VCC PIN OF
J 2
(-1175 3525);
DISPLAY 1.021277 (-1175 3525);
PAINT ORANGE (-1175 3525);
FORCEPROP 0 LAST L3 74LVC2G07
J 2
(-1175 3450);
DISPLAY 1.021277 (-1175 3450);
PAINT ORANGE (-1175 3450);
FORCEPROP 0 LAST L1 PLACE 0.1UF CAP
J 2
(-1175 3600);
DISPLAY 1.021277 (-1175 3600);
PAINT ORANGE (-1175 3600);
FORCEPROP 2 LAST CDS_LIB mstr_symbols
J 0
(-1400 3725);
PAINT ORANGE (-1400 3725);
DISPLAY INVISIBLE (-1400 3725);
FORCEPROP 1 LAST COMMENT_BODY TRUE
J 0
(-1375 3825);
DISPLAY 0.978723 (-1375 3825);
PAINT ORANGE (-1375 3825);
DISPLAY INVISIBLE (-1375 3825);
FORCEADD DNS..2
(-6020 1720);
PAINT RED (-6020 1720);
FORCEPROP 2 LAST CDS_LIB mstr_misc
J 0
(-6020 1720);
PAINT ORANGE (-6020 1720);
DISPLAY INVISIBLE (-6020 1720);
FORCEPROP 1 LAST COMMENT_BODY TRUE
R 1
J 0
(-5945 1495);
DISPLAY 0.872340 (-5945 1495);
PAINT GREEN (-5945 1495);
DISPLAY INVISIBLE (-5945 1495);
FORCEADD DNS..2
(-2895 1820);
PAINT RED (-2895 1820);
FORCEPROP 2 LAST CDS_LIB mstr_misc
J 0
(-2895 1820);
PAINT ORANGE (-2895 1820);
DISPLAY INVISIBLE (-2895 1820);
FORCEPROP 1 LAST COMMENT_BODY TRUE
R 1
J 0
(-2820 1595);
DISPLAY 0.872340 (-2820 1595);
PAINT GREEN (-2820 1595);
DISPLAY INVISIBLE (-2820 1595);
FORCEADD DNS..2
(-6595 2345);
PAINT RED (-6595 2345);
FORCEPROP 2 LAST CDS_LIB mstr_misc
J 0
(-6595 2345);
PAINT ORANGE (-6595 2345);
DISPLAY INVISIBLE (-6595 2345);
FORCEPROP 1 LAST COMMENT_BODY TRUE
R 1
J 0
(-6520 2120);
DISPLAY 0.872340 (-6520 2120);
PAINT GREEN (-6520 2120);
DISPLAY INVISIBLE (-6520 2120);
FORCEADD INTEL_CORP_BPAGE..1
(0 0);
FORCEPROP 1 LAST CDS_CON_LAST_MODIFIED Fri Jun 16 17:48:58 2017
J 0
(-1425 325);
DISPLAY 1.361702 (-1425 325);
PAINT GREEN (-1425 325);
DISPLAY INVISIBLE (-1425 325);
FORCEPROP 1 LAST CUSTOM_TXT_CDS <CURRENT_DESIGN_SHEET> OF <TOTAL_DESIGN_SHEETS>
J 0
(-500 25);
PAINT ORANGE (-500 25);
FORCEPROP 1 LAST CUSTOM_TXT_CDS <CON_LAST_MODIFIED>
J 0
(-4000 100);
PAINT ORANGE (-4000 100);
FORCEPROP 2 LAST CUSTOM_TXT_CDS <XR_PAGE_TITLE>
J 0
(-7890 5250);
DISPLAY 0.638298 (-7890 5250);
PAINT PINK (-7890 5250);
DISPLAY INVISIBLE (-7890 5250);
FORCEPROP 1 LAST SCH_TITLE BMC MISC (1 OF 2)
J 0
(-7950 50);
DISPLAY 1.212766 (-7950 50);
PAINT ORANGE (-7950 50);
FORCEPROP 2 LAST PAGE_BORDER TRUE
J 0
(-7890 5250);
DISPLAY 0.851064 (-7890 5250);
PAINT PINK (-7890 5250);
DISPLAY INVISIBLE (-7890 5250);
FORCEPROP 2 LAST CDS_LIB mstr_symbols
J 0
(0 0);
DISPLAY 1.361702 (0 0);
PAINT ORANGE (0 0);
DISPLAY INVISIBLE (0 0);
FORCEPROP 1 LAST COMMENT_BODY TRUE
J 0
(12 12);
DISPLAY 0.617021 (12 12);
PAINT GREEN (12 12);
DISPLAY INVISIBLE (12 12);
FORCEPROP 2 LAST CDS_XR_PAGE_TITLE CR-156 : @BASEBOARD_FAB2_LIB.BASEBOARD_FAB2(SCH_1):PAGE156
J 0
(-7890 5250);
DISPLAY 0.638298 (-7890 5250);
PAINT PINK (-7890 5250);
DISPLAY INVISIBLE (-7890 5250);
FORCEADD CAD_NOTE..1
(-1400 4800);
FORCEPROP 0 LAST L3 74LVC2G07
J 2
(-1175 4525);
DISPLAY 1.021277 (-1175 4525);
PAINT ORANGE (-1175 4525);
FORCEPROP 0 LAST L1 PLACE 0.1UF CAP
J 2
(-1175 4675);
DISPLAY 1.021277 (-1175 4675);
PAINT ORANGE (-1175 4675);
FORCEPROP 0 LAST L2 NEXT TO VCC PIN OF
J 2
(-1175 4600);
DISPLAY 1.021277 (-1175 4600);
PAINT ORANGE (-1175 4600);
FORCEPROP 1 LAST COMMENT_BODY TRUE
J 0
(-1375 4900);
DISPLAY 0.978723 (-1375 4900);
PAINT ORANGE (-1375 4900);
DISPLAY INVISIBLE (-1375 4900);
FORCEPROP 2 LAST CDS_LIB mstr_symbols
J 0
(-1400 4800);
PAINT ORANGE (-1400 4800);
DISPLAY INVISIBLE (-1400 4800);
FORCEADD DNS..2
(-2895 1545);
PAINT RED (-2895 1545);
FORCEPROP 2 LAST CDS_LIB mstr_misc
J 0
(-2895 1545);
PAINT ORANGE (-2895 1545);
DISPLAY INVISIBLE (-2895 1545);
FORCEPROP 1 LAST COMMENT_BODY TRUE
R 1
J 0
(-2820 1320);
DISPLAY 0.872340 (-2820 1320);
PAINT GREEN (-2820 1320);
DISPLAY INVISIBLE (-2820 1320);
FORCEADD DNS..2
(-7645 1695);
PAINT RED (-7645 1695);
FORCEPROP 2 LAST CDS_LIB mstr_misc
J 0
(-7645 1695);
PAINT ORANGE (-7645 1695);
DISPLAY INVISIBLE (-7645 1695);
FORCEPROP 1 LAST COMMENT_BODY TRUE
R 1
J 0
(-7570 1470);
DISPLAY 0.872340 (-7570 1470);
PAINT GREEN (-7570 1470);
DISPLAY INVISIBLE (-7570 1470);
WIRE 16 -1 (-4150 4800)(-4150 4675);
WIRE 16 -1 (-3825 4675)(-4150 4675);
WIRE 16 -1 (-4150 4675)(-4150 4550);
WIRE 16 -1 (-3825 4550)(-3825 4675);
WIRE 16 -1 (-2400 4800)(-2400 4675);
WIRE 16 -1 (-2275 4675)(-2400 4675);
WIRE 16 -1 (-2550 4675)(-2400 4675);
WIRE 16 -1 (-2550 4675)(-2550 4550);
WIRE 16 -1 (-2275 4525)(-2275 4675);
WIRE 16 -1 (-6825 3225)(-6825 3125);
WIRE 16 -1 (-7275 4350)(-7275 4475);
WIRE 16 -1 (-7275 4475)(-7500 4475);
WIRE 16 -1 (-4150 3600)(-4150 3475);
WIRE 16 -1 (-3825 3475)(-4150 3475);
WIRE 16 -1 (-4150 3475)(-4150 3350);
WIRE 16 -1 (-3825 3350)(-3825 3475);
WIRE 16 -1 (-3200 3650)(-3200 3600);
WIRE 16 -1 (-3200 3600)(-2700 3600);
WIRE 16 -1 (-3200 3600)(-3200 3550);
WIRE 16 -1 (-2700 3600)(-2700 2950);
WIRE 16 -1 (-2700 2950)(-2900 2950);
WIRE 16 -1 (-3200 3300)(-3200 3350);
WIRE 16 -1 (-3200 4450)(-3200 4500);
WIRE 16 -1 (-3200 4800)(-3200 4750);
WIRE 16 -1 (-3200 4750)(-2700 4750);
WIRE 16 -1 (-3200 4750)(-3200 4700);
WIRE 16 -1 (-2700 4750)(-2700 4150);
WIRE 16 -1 (-2700 4150)(-2900 4150);
WIRE 16 -1 (-7275 3600)(-7275 3700);
WIRE 16 -1 (-7275 3700)(-7475 3700);
WIRE 16 -1 (-4275 475)(-4275 575);
WIRE 16 -1 (-4275 575)(-4275 775);
WIRE 16 -1 (-4275 575)(-4100 575);
WIRE 16 -1 (-4275 775)(-4275 975);
WIRE 16 -1 (-4275 775)(-4100 775);
WIRE 16 -1 (-4275 975)(-4100 975);
WIRE 16 -1 (-2175 475)(-2175 575);
WIRE 16 -1 (-2175 575)(-2175 775);
WIRE 16 -1 (-2175 575)(-2000 575);
WIRE 16 -1 (-2175 775)(-2000 775);
WIRE 16 -1 (-2175 1050)(-2175 975);
WIRE 16 -1 (-2175 975)(-2000 975);
WIRE 16 -1 (-7650 1900)(-7650 1800);
WIRE 16 -1 (-7650 1125)(-7650 1225);
WIRE 16 -1 (-6025 1150)(-6025 1250);
WIRE 16 -1 (-6025 1925)(-6025 1825);
WIRE 16 -1 (-3650 4150)(-3650 4000);
WIRE 16 -1 (-3550 4150)(-3650 4150);
WIRE 16 -1 (-3650 2950)(-3650 2800);
WIRE 16 -1 (-3550 2950)(-3650 2950);
WIRE 3 682 (-7750 3450)(-7150 3450);
WIRE 3 682 (-7750 4750)(-7750 3450);
WIRE 3 682 (-7150 3450)(-7150 4750);
WIRE 3 682 (-7150 4750)(-7750 4750);
WIRE 16 -1 (-1600 4200)(-750 4200);
WIRE 16 3135 (-4975 2650)(-75 2650);
WIRE 16 3135 (-4975 4050)(-4975 2650);
WIRE 16 3135 (-4975 4050)(-4975 4850);
WIRE 16 3135 (-7875 4050)(-4975 4050);
WIRE 16 -1 (-3150 1825)(-3000 1825);
WIRE 16 -1 (-4025 1550)(-3150 1550);
FORCEPROP 2 LAST SIG_NAME FM_CPU_BMC_INIT
J 0
(-4010 1560);
DISPLAY 0.617021 (-4010 1560);
PAINT ORANGE (-4010 1560);
WIRE 16 -1 (-3150 1550)(-3150 1825);
WIRE 16 -1 (-3150 1550)(-3000 1550);
WIRE 16 3135 (-7875 3400)(-5025 3400);
WIRE 16 -1 (-7500 4525)(-6575 4525);
FORCEPROP 2 LAST SIG_NAME SMB_HOST_STBY_LVC3_SDA
J 2
(-6585 4535);
DISPLAY 0.617021 (-6585 4535);
PAINT ORANGE (-6585 4535);
WIRE 16 -1 (-6825 2775)(-6675 2775);
WIRE 16 -1 (-6825 2925)(-6825 2775);
WIRE 16 -1 (-7475 2775)(-6825 2775);
FORCEPROP 2 LAST SIG_NAME IRQ_BMC_PCH_NMI_STBY_N
J 0
(-7460 2785);
DISPLAY 0.617021 (-7460 2785);
PAINT ORANGE (-7460 2785);
WIRE 16 -1 (-3825 4200)(-4575 4200);
FORCEPROP 2 LAST SIG_NAME RST_BMC_SYSRST_BTN_OUT_N
J 0
(-4535 4210);
DISPLAY 0.617021 (-4535 4210);
PAINT ORANGE (-4535 4210);
WIRE 16 -1 (-3825 4350)(-3825 4200);
WIRE 16 -1 (-3550 4200)(-3825 4200);
WIRE 16 -1 (-1600 4100)(-750 4100);
WIRE 16 -1 (-4575 4100)(-4150 4100);
FORCEPROP 2 LAST SIG_NAME FM_BMC_PWRBTN_OUT_N
J 0
(-4535 4110);
DISPLAY 0.617021 (-4535 4110);
PAINT ORANGE (-4535 4110);
WIRE 16 -1 (-4150 4100)(-3550 4100);
WIRE 16 -1 (-4150 4350)(-4150 4100);
WIRE 3 2175 (-3500 3950)(-2950 3950);
WIRE 3 2175 (-2950 4350)(-2950 3950);
WIRE 3 2175 (-3500 4350)(-3500 3950);
WIRE 3 2175 (-3500 4350)(-2950 4350);
WIRE 16 -1 (-6475 2775)(-5900 2775);
FORCEPROP 2 LAST SIG_NAME IRQ_BMC_PCH_NMI_STBY_R_N
J 0
(-6435 2785);
DISPLAY 0.617021 (-6435 2785);
PAINT ORANGE (-6435 2785);
WIRE 16 -1 (-2900 3000)(-2325 3000);
WIRE 16 -1 (-2325 3000)(-2325 4200);
FORCEPROP 2 LAST SIG_NAME RST_BMC_SYSRST_BTN_OUT_B_R_N
R 1
J 0
(-2360 3010);
DISPLAY 0.617021 (-2360 3010);
PAINT ORANGE (-2360 3010);
FORCEPROP 2 LASTPROP $XRERR UNIQUE?
J 0
(-2600 3010);
DISPLAY 0.638298 (-2600 3010);
PAINT MONO (-2600 3010);
DISPLAY INVISIBLE (-2600 3010);
WIRE 16 -1 (-2900 4200)(-2325 4200);
WIRE 16 -1 (-2325 4200)(-2275 4200);
WIRE 16 -1 (-2275 4200)(-1800 4200);
WIRE 16 -1 (-2275 4325)(-2275 4200);
WIRE 16 -1 (-2900 2900)(-2275 2900);
WIRE 16 -1 (-2275 2900)(-2275 4100);
WIRE 16 -1 (-2275 4100)(-1800 4100);
FORCEPROP 2 LAST SIG_NAME FM_PCH_PWRBTN_R_N
J 0
(-2260 4110);
DISPLAY 0.617021 (-2260 4110);
PAINT ORANGE (-2260 4110);
FORCEPROP 2 LASTPROP $XRERR UNIQUE?
J 0
(-2500 4110);
DISPLAY 0.638298 (-2500 4110);
PAINT MONO (-2500 4110);
DISPLAY INVISIBLE (-2500 4110);
WIRE 16 -1 (-2550 4350)(-2550 4100);
WIRE 16 -1 (-2275 4100)(-2550 4100);
WIRE 16 -1 (-2900 4100)(-2550 4100);
WIRE 16 -1 (-3825 3000)(-4575 3000);
FORCEPROP 2 LAST SIG_NAME RST_PCH_SYSRST_BTN_OUT_N
J 0
(-4535 3010);
DISPLAY 0.617021 (-4535 3010);
PAINT ORANGE (-4535 3010);
WIRE 16 -1 (-3550 3000)(-3825 3000);
WIRE 16 -1 (-3825 3150)(-3825 3000);
WIRE 16 -1 (-4575 2900)(-4150 2900);
FORCEPROP 2 LAST SIG_NAME FM_PCH_PWRBTN_OUT_N
J 0
(-4535 2910);
DISPLAY 0.617021 (-4535 2910);
PAINT ORANGE (-4535 2910);
WIRE 16 -1 (-4150 2900)(-3550 2900);
WIRE 16 -1 (-4150 3150)(-4150 2900);
WIRE 3 2175 (-3500 2750)(-2950 2750);
WIRE 3 2175 (-2950 3150)(-2950 2750);
WIRE 3 2175 (-3500 3150)(-3500 2750);
WIRE 3 2175 (-3500 3150)(-2950 3150);
WIRE 16 -1 (-6500 2350)(-5900 2350);
FORCEPROP 2 LAST SIG_NAME FM_ADR_SMI_GPIO_N
J 0
(-6410 2360);
DISPLAY 0.617021 (-6410 2360);
PAINT ORANGE (-6410 2360);
WIRE 16 -1 (-6700 2350)(-7400 2350);
FORCEPROP 2 LAST SIG_NAME FM_MEM_THERM_EVENT_LVT3_N
J 0
(-7360 2360);
DISPLAY 0.617021 (-7360 2360);
PAINT ORANGE (-7360 2360);
WIRE 16 -1 (-7650 1600)(-7650 1525);
WIRE 16 -1 (-6600 1525)(-7650 1525);
FORCEPROP 2 LAST SIG_NAME FM_CPU0_SM_WP
J 0
(-7210 1535);
DISPLAY 0.617021 (-7210 1535);
PAINT ORANGE (-7210 1535);
WIRE 16 -1 (-7650 1425)(-7650 1525);
WIRE 16 -1 (-6025 1625)(-6025 1550);
WIRE 16 -1 (-4975 1550)(-6025 1550);
FORCEPROP 2 LAST SIG_NAME FM_CPU1_SM_WP
J 0
(-5585 1560);
DISPLAY 0.617021 (-5585 1560);
PAINT ORANGE (-5585 1560);
WIRE 16 -1 (-6025 1450)(-6025 1550);
WIRE 16 -1 (-6700 850)(-6525 850);
WIRE 16 -1 (-7300 700)(-6700 700);
FORCEPROP 2 LAST SIG_NAME SMB_LAN_STBY_LVC3_SDA
J 0
(-7260 710);
DISPLAY 0.617021 (-7260 710);
PAINT ORANGE (-7260 710);
WIRE 16 -1 (-6700 700)(-6700 850);
WIRE 16 -1 (-6700 700)(-6525 700);
WIRE 16 -1 (-6700 550)(-6525 550);
WIRE 16 -1 (-7300 400)(-6700 400);
FORCEPROP 2 LAST SIG_NAME SMB_LAN_STBY_LVC3_SCL
J 0
(-7260 410);
DISPLAY 0.617021 (-7260 410);
PAINT ORANGE (-7260 410);
WIRE 16 -1 (-6700 400)(-6700 550);
WIRE 16 -1 (-6700 400)(-6525 400);
WIRE 16 -1 (-6325 850)(-5400 850);
FORCEPROP 2 LAST SIG_NAME SMB_PIROM_CPU1_SDA
J 2
(-5385 860);
DISPLAY 0.617021 (-5385 860);
PAINT ORANGE (-5385 860);
WIRE 16 -1 (-6325 700)(-5400 700);
FORCEPROP 2 LAST SIG_NAME SMB_PIROM_CPU0_SDA
J 2
(-5385 710);
DISPLAY 0.617021 (-5385 710);
PAINT ORANGE (-5385 710);
WIRE 16 -1 (-6325 550)(-5400 550);
FORCEPROP 2 LAST SIG_NAME SMB_PIROM_CPU1_SCL
J 2
(-5385 560);
DISPLAY 0.617021 (-5385 560);
PAINT ORANGE (-5385 560);
WIRE 16 -1 (-6325 400)(-5400 400);
FORCEPROP 2 LAST SIG_NAME SMB_PIROM_CPU0_SCL
J 2
(-5385 410);
DISPLAY 0.617021 (-5385 410);
PAINT ORANGE (-5385 410);
WIRE 16 -1 (-2800 1825)(-1875 1825);
FORCEPROP 2 LAST SIG_NAME H_CPU0_BMCINIT
J 2
(-1875 1835);
DISPLAY 0.617021 (-1875 1835);
PAINT ORANGE (-1875 1835);
WIRE 16 -1 (-2800 1550)(-1875 1550);
FORCEPROP 2 LAST SIG_NAME H_CPU1_BMCINIT
J 2
(-1875 1560);
DISPLAY 0.617021 (-1875 1560);
PAINT ORANGE (-1875 1560);
WIRE 16 -1 (-3900 975)(-3000 975);
FORCEPROP 2 LAST SIG_NAME PD_PIROM_CPU0_ADDR0
J 0
(-3610 985);
DISPLAY 0.617021 (-3610 985);
PAINT ORANGE (-3610 985);
WIRE 16 -1 (-3900 775)(-3000 775);
FORCEPROP 2 LAST SIG_NAME PD_PIROM_CPU0_ADDR1
J 0
(-3610 785);
DISPLAY 0.617021 (-3610 785);
PAINT ORANGE (-3610 785);
WIRE 16 -1 (-3900 575)(-3000 575);
FORCEPROP 2 LAST SIG_NAME PD_PIROM_CPU0_ADDR2
J 0
(-3610 585);
DISPLAY 0.617021 (-3610 585);
PAINT ORANGE (-3610 585);
WIRE 16 -1 (-1800 975)(-900 975);
FORCEPROP 2 LAST SIG_NAME PU_PIROM_CPU1_ADDR0
J 0
(-1510 985);
DISPLAY 0.617021 (-1510 985);
PAINT ORANGE (-1510 985);
WIRE 16 -1 (-1800 775)(-900 775);
FORCEPROP 2 LAST SIG_NAME PD_PIROM_CPU1_ADDR1
J 0
(-1510 785);
DISPLAY 0.617021 (-1510 785);
PAINT ORANGE (-1510 785);
WIRE 16 -1 (-1800 575)(-900 575);
FORCEPROP 2 LAST SIG_NAME PD_PIROM_CPU1_ADDR2
J 0
(-1510 585);
DISPLAY 0.617021 (-1510 585);
PAINT ORANGE (-1510 585);
WIRE 16 -1 (-7475 3650)(-6550 3650);
FORCEPROP 2 LAST SIG_NAME SMB_SMLINK0_STBY_LVC3_SCL
J 2
(-6560 3660);
DISPLAY 0.617021 (-6560 3660);
PAINT ORANGE (-6560 3660);
WIRE 16 -1 (-7475 3750)(-6550 3750);
FORCEPROP 2 LAST SIG_NAME SMB_SMLINK0_STBY_LVC3_SDA
J 2
(-6560 3760);
DISPLAY 0.617021 (-6560 3760);
PAINT ORANGE (-6560 3760);
WIRE 16 -1 (-7500 4425)(-6575 4425);
FORCEPROP 2 LAST SIG_NAME SMB_HOST_STBY_LVC3_SCL
J 2
(-6585 4435);
DISPLAY 0.617021 (-6585 4435);
PAINT ORANGE (-6585 4435);
DOT 1 (-2400 4675);
DOT 1 (-2550 4100);
DOT 1 (-2175 575);
DOT 1 (-3150 1550);
DOT 1 (-4150 4675);
DOT 1 (-4150 4100);
DOT 1 (-4975 4050);
DOT 1 (-4275 775);
DOT 1 (-4275 575);
DOT 1 (-6025 1550);
DOT 1 (-6825 2775);
DOT 1 (-6700 700);
DOT 1 (-6700 400);
DOT 1 (-7650 1525);
DOT 1 (-3825 4200);
DOT 1 (-2275 4200);
DOT 1 (-3200 4750);
DOT 1 (-2275 4100);
DOT 1 (-4150 3475);
DOT 1 (-2325 4200);
DOT 1 (-3825 3000);
DOT 1 (-3200 3600);
DOT 1 (-4150 2900);
FORCENOTE
TP FAB1 CHANGE CONFIG 0422
(-7125 3475) 0;
DISPLAY LEFT (-7125 3475);
DISPLAY 1.021277 (-7125 3475);
PAINT RED (-7125 3475);
FORCENOTE
ME DEBUG HEADER
(-7100 4725) 0;
DISPLAY LEFT (-7100 4725);
DISPLAY 1.021277 (-7100 4725);
PAINT PURPLE (-7100 4725);
FORCENOTE
BMC DEBUG HEADER
(-7100 3925) 0;
DISPLAY LEFT (-7100 3925);
DISPLAY 1.021277 (-7100 3925);
PAINT PURPLE (-7100 3925);
FORCENOTE
ROOM=SM_THERM
(-7775 200) 0;
DISPLAY LEFT (-7775 200);
DISPLAY 0.617021 (-7775 200);
PAINT PURPLE (-7775 200);
FORCENOTE
TP FAB1 CHANGE PN 1225
(-3500 3875) 0;
DISPLAY LEFT (-3500 3875);
DISPLAY 1.021277 (-3500 3875);
PAINT RED (-3500 3875);
FORCENOTE
TP FAB1 CHANGE PN 1225
(-3500 2675) 0;
DISPLAY LEFT (-3500 2675);
DISPLAY 1.021277 (-3500 2675);
PAINT RED (-3500 2675);
QUIT
